# ZAIUS-MB-PVT-X04-BOM_X31_20180131_Final.xls.xlsx — PWA BOM (bom)
| FOXCONN TECHNOLOGY GROUP |  |  |  |  |  |  |  |  |  |  |  |  |  |  |  |  |  |  |  |
| BILL OF MATERIAL |  |  |  |  |  |  |  |  |  |  |  |  |  |  |  |  |  |  |  |
| REV OF  BOM | X31 | CUSTOMER |  | <name> |  | CUSTOMER P/N |  | PWA P/N： | PWA DESCRIPTION |  |  |  | PRODUCT CODE |  |  | PWA  REV | X04 | DATE | 43131 |
| Sourcing (Single/Sole/Multi) | Critical Commodity (Y or N) | Component Class (1, 2, other) | Customer PSL (Y or N) | Line Item | Item Number | Foxconn P/N | Customer P/N | Part Description | Manufacturer  Full Name | Manufacturer  Part Number | Qty | RoHS Status | Location | CC Qual Build: | Qual by (Customer / ODM ?) | The Date of Change Part or Add 2nd Source | Configuration Identifier | Customer Comments | ODM Comments |
| Single |  |  |  | 1 | 1 | 0101FBQ00-000-G | 40000716-05 | PCB,Zaius-MB PVT-X04,OSP,Gre,22L,22.20*13.00,G | GOLD CIRCUIT ELECTRONICS LTD. | 0101FBQ00-000-G | 1 | G | PCB |  |  |  |  |  |  |
| Multi | N | ND | Y(2) | 2 | 2 | 890100800-024-G |  | Battery,PANASONIC,CR-2032L/BE,Lithium,3V,225mAH,G | PANASONIC INDUSTRIAL CO.,LTD. | CR-2032L/BE | 1 | G | BAT1 |  |  |  |  |  |  |
|  |  |  |  |  | 2 | 6032-101-501 |  | Battery,VARTA,CR-2032,Lithium,3V,230mAH,G | Varta | 6032-101-501 |  | G |  |  |  |  |  |  |  |
| Multi | ND |  | N | 3 | 3 | 622202200-022-G |  | SPET CAP,220uF,+/-20%,10V,105℃,G,SMD2816,ESR<=40mOhm | SANYO ELECTRIC CO., LTD. | 10TPB220ML | 6 | G | CE1,CE4,CE5,CE6,CE33,CE34 |  |  |  |  |  |  |
|  |  |  |  |  | 3 | 622202201-025-G |  | SPET CAP,220uF,+/-20%,10V,105℃,G,SMD2816,ESR<=40mOhm | KEMET ELECTRONICS CORPORATION | T520D227M010ATE040 |  | G |  |  |  |  |  |  |  |
| Multi | Y |  | N | 4 | 4 | 62120FL00-022-G |  | SPEA CAP,100uF,+/-20%,16V,105℃,G,SMD6.3*5.9,ESR<=24mOhm | SANYO ELECTRIC CO., LTD. | 16SVPC100M | 4 | G | CE17,CE18,CE19,CE20 |  |  |  |  |  |  |
|  |  |  |  |  | 4 | 62120CB00-025-G |  | ECAP,SPEA,100uF,+/-20%,16V,105C,G,SMD6.3*5.7,ESR<=25mOhm | KEMET ELECTRONICS CORPORATION | A765EB107M1CLAE025 |  | G |  |  |  |  |  |  |  |
| Sole | Y | ND | Y(5) | 5 | 5 | 62120BE00-015-G |  | SP-CAP,100uF,+/-20%,16V,105℃,G,SMD2816,ESR<=12mOhm | MURATA ELEC. NORTH AMERICA | ECASD91C107M012K01 | 10 | G | CE21,CE22,CE23,CE24,CE25,CE26,CE27,CE28,CE29,CE30 |  |  |  |  |  |  |
| Multi | Y | ND | Y(3) | 6 | 6 | 62011U701-015-G |  | CAP,10nF,+/-10%,X7R,6.3V,G,SMD0402 | MURATA ELEC. NORTH AMERICA | GRM155R70J103K | 43 | G | C5,C6,C9,C14,C15,C189,C190,C730,C731,C734,C737,C738,C905,C906,C1513,C1628,C1629,C1630,C1631,C1632,C1633,C1634,C1635,C1636,C1637,C1638,C1639,C1640,C1641,C1642,C1643,C1644,C1667,C1730,C1731,C1732,C1733,C1742,C1743,C1744,C1745,C2048,C2087 |  |  |  |  |  |  |
|  |  |  |  |  | 6 | 62011U700-023-G |  | CAP,10nF,+/-10%,X7R,6.3V,G,SMD0402 | TAIYO ELECTRIC IND.CO.LTD | JMK105B7103KV-F |  | G |  |  |  |  |  |  |  |
| Multi | ND |  | Y(3) | 7 | 7 | 620106200-015-G |  | CAP,10nF,+/-10%,X7R,16V,G,SMD0402 | MURATA ELEC. NORTH AMERICA | GRM155R71C103KA01D | 37 | G | PUAC2,PSAC2,PRAC2,PQAC2,PPAC2,PIAC2,PFAC2,PEAC2,PANC7,PBNC8,PBNC15,PANC15,C33,C34,C698,C700,C701,C702,C705,C750,C1714,C1718,C1722,C1726,C2026,C2064,C2065,C2085,C2086,C2088,C2089,C2090,C2091,C2093,C2094,C2115,C2116 |  |  |  |  |  |  |
|  |  |  |  |  | 7 | 620106200-026-G |  | CAP,10nF,+/-10%,X7R,16V,G,SMD0402 | SAMSUNG SEMICONDUCTOR | CL05B103KO5NNNC |  | G |  |  |  |  |  |  |  |
|  |  |  |  |  | 7 | 620106200-023-G |  | CAP,10nF,+/-10%,X7R,16V,G,SMD0402 | TAIYO ELECTRIC IND.CO.LTD | EMK105B7103KV-F |  | G |  |  |  |  |  |  |  |
| Multi | ND | ND | Y(3) | 8 | 8 | 620103700-015-G |  | CAP,100nF,+/-10%,X7R,10V,G,SMD0402 | MURATA ELEC. NORTH AMERICA | GRM155R71A104K | 170 | G | PHAC5,PUAC10,PSLC10,PSIC10,PSFC10,PSEC10,PSDC10,PSAC10,PRAC10,PQAC10,PPAC10,PIAC10,PFAC10,PEEC10,PEDC10,PEAC10,C35,C84,C85,C86,C87,C88,C89,C90,C91,C92,C93,C94,C98,C99,C100,C101,C102,C103,C104,C105,C106,C107,C108,C687,C688,C691,C692,C693,C695,C696,C706,C707,C708,C709,C710,C711,C712,C713,C714,C715,C716,C717,C718,C720,C721,C722,C723,C724,C725,C751,C793,C801,C802,C803,C804,C805,C806,C807,C808,C809,C810,C815,C816,C817,C818,C819,C820,C821,C822,C823,C824,C1503,C1504,C1691,C1692,C1693,C1694,C1699,C1700,C1701,C1702,C2000,C2001,C2002,C2003,C2021,C2022,C2023,C2024,C2025,C2027,C2034,C2036,C2037,C2038,C2039,C2040,C2042,C2043,C2044,C2045,C2046,C2049,C2050,C2051,C2052,C2053,C2054,C2055,C2056,C2057,C2058,C2059,C2060,C2061,C2062,C2067,C2068,C2073,C2075,C2077,C2078,C2079,C2080,C2083,C2084,C2095,C2096,C2099,C2100,C2101,C2102,C2103,C2104,C2105,C2106,C2117,C2118,C2119,C2123,C2125,C2128,C2130,C2133,C2134,C2135,C2142,C2144,C2157,C2158,C2159,C2160,C2161,C2186 |  |  |  |  |  |  |
|  |  |  |  |  | 8 | 620103700-023-G |  | CAP,100nF,+/-10%,X7R,10V,G,SMD0402 | TAIYO ELECTRIC IND.CO.LTD | LMK105B7104KV-F |  | G |  |  |  |  |  |  |  |
|  |  |  |  |  | 8 | 620103700-026-G |  | CAP,100nF,+/-10%,X7R,10V,G,SMD0402 | SAMSUNG SEMICONDUCTOR | CL05B104KP5NNNC |  | G |  |  |  |  |  |  |  |
| Multi | ND | ND | Y(1) | 9 | 9 | 62010P501-015-G |  | CAP,1nF,+/-10%,X7R,16V,G,SMD0402 | MURATA ELEC. NORTH AMERICA | GRM155R71C102KA01D | 58 | G | C36,C191,C193,C195,C197,C207,C208,C217,C218,C219,C220,C221,C222,C223,C315,C317,C319,C321,C439,C441,C443,C445,C563,C565,C567,C569,C699,C703,C704,C749,C752,C907,C909,C911,C913,C1031,C1033,C1035,C1037,C1155,C1157,C1159,C1161,C1279,C1281,C1283,C1285,C1514,C1517,C1519,C1716,C1720,C1724,C1728,C1947,C1948,C2047,C2124 |  |  |  |  |  |  |
|  |  |  |  |  | 9 | 62010P500-026-G |  | CAP,1nF,+/-10%,X7R,16V,G,SMD0402 | SAMSUNG SEMICONDUCTOR | CL05B102KO5NNNC |  | G |  |  |  |  |  |  |  |
|  |  |  |  |  | 9 | 62010P500-023-G |  | CAP,1nF,+/-10%,X7R,16V,G,SMD0402 | TAIYO ELECTRIC IND.CO.LTD | EMK105B7102KV-F |  | G |  |  |  |  |  |  |  |
| Multi | ND | ND | Y(4) | 10 | 10 | 62011SJ00-026-G |  | CAP,470nF,+/-10%,X7R,6.3V,G,SMD0402 | SAMSUNG SEMICONDUCTOR | CL05B474KQ5NNNC | 160 | G | C38,C39,C47,C78,C95,C96,C137,C141,C143,C145,C148,C150,C183,C185,C186,C188,C236,C241,C242,C243,C244,C251,C252,C253,C254,C269,C270,C271,C272,C287,C288,C289,C290,C365,C366,C367,C368,C375,C376,C377,C378,C393,C394,C395,C396,C411,C412,C413,C414,C489,C490,C491,C492,C499,C500,C501,C502,C517,C518,C519,C520,C535,C536,C537,C538,C613,C614,C615,C616,C623,C624,C625,C626,C641,C642,C643,C644,C659,C660,C661,C662,C766,C768,C786,C791,C792,C811,C847,C851,C852,C853,C854,C857,C858,C866,C902,C957,C958,C959,C960,C967,C968,C969,C970,C985,C986,C987,C988,C1003,C1004,C1005,C1006,C1081,C1082,C1083,C1084,C1091,C1092,C1093,C1094,C1109,C1110,C1111,C1112,C1127,C1128,C1129,C1130,C1205,C1206,C1207,C1208,C1215,C1216,C1217,C1218,C1233,C1234,C1235,C1236,C1251,C1252,C1253,C1254,C1329,C1330,C1331,C1332,C1339,C1340,C1341,C1342,C1357,C1358,C1359,C1360,C1375,C1376,C1377,C1378 |  |  |  |  |  |  |
|  |  |  |  |  | 10 | 62011SJ00-023-G |  | CAP,470nF,+/-10%,X7R,6.3V,G,SMD0402 | TAIYO ELECTRIC IND.CO.LTD | JMK105B7474KV-F |  | G |  |  |  |  |  |  |  |
| Multi | Y | ND | Y(1) | 11 | 11 | 62012WD00-015-G |  | CAP,4.7uF,+/-20%,X6S,6.3V,G,SMD0402 | MURATA ELEC. NORTH AMERICA | GRM155C80J475MEAAD | 20 | G | C40,C53,C56,C62,C65,C73,C74,C147,C689,C690,C694,C764,C767,C775,C777,C787,C788,C790,C860,C2166 |  |  |  |  |  |  |
|  |  |  |  |  | 11 | 62012WD00-023-G |  | CAP,4.7uF,+/-20%,X6S,6.3V,G,SMD0402 | TAIYO ELECTRIC IND.CO.LTD | JMK105BC6475MV-F |  | G |  |  |  |  |  |  |  |
| Multi | ND | ND | N | 12 | 12 | 62012NU00-015-G |  | CAP,1uF,+/-10%,X7R,6.3V,G,SMD0402 | MURATA ELEC. NORTH AMERICA | GRM155R70J105KA12D | 109 | G | C41,C42,C43,C44,C45,C48,C49,C50,C51,C52,C54,C55,C57,C58,C59,C61,C64,C67,C68,C71,C72,C134,C136,C146,C149,C159,C160,C169,C170,C181,C199,C200,C201,C228,C697,C754,C755,C756,C758,C759,C760,C761,C763,C765,C769,C770,C771,C772,C773,C776,C778,C779,C780,C782,C783,C784,C789,C799,C848,C849,C855,C875,C876,C885,C886,C903,C916,C917,C1475,C1482,C1483,C1500,C1501,C1505,C1506,C1507,C1508,C1509,C1510,C1512,C1572,C1573,C1574,C1575,C1578,C1579,C1580,C1581,C1582,C1583,C1586,C1587,C1588,C1589,C1590,C1591,C1593,C1594,C1595,C1599,C1602,C1605,C1650,C1748,C1833,C2072,C2074,C2076,C2143 |  |  |  |  |  |  |
|  |  |  |  |  | 12 | 62012NU00-026-G |  | CAP,1uF,+/-10%,X7R,6.3V,G,SMD0402 | SAMSUNG SEMICONDUCTOR | CL05B105KQ5NQNC |  | G |  |  |  |  |  |  |  |
| Sole | ND |  | Y(3) | 13 | 13 | 62012P100-015-G |  | CAP,2.2uF,+/-20%,X7S,10V,G,SMD0402 | MURATA ELEC. NORTH AMERICA | GRM155C71A225M | 28 | G | PSTC5,PSLC5,PSFC5,PSEC5,PSDC5,PQPC5,PFRC5,PEEC5,PEDC5,C46,C63,C69,C79,C142,C144,C157,C167,C226,C234,C774,C781,C785,C813,C856,C864,C873,C883,C2011 |  |  |  |  |  |  |
| Multi | Y | 2 | Y(3) | 14 | 14 | 62011DF01-015-G |  | CAP,220nF,+/-10%,X7R,16V,G,SMD0402 | MURATA ELEC. NORTH AMERICA | GRM155R71C224K | 283 | G | C66,C70,C75,C76,C77,C81,C82,C97,C109,C110,C111,C112,C113,C114,C115,C116,C117,C118,C119,C120,C121,C122,C123,C124,C125,C126,C127,C128,C129,C130,C131,C132,C133,C135,C139,C140,C151,C152,C153,C154,C155,C156,C161,C162,C163,C164,C165,C166,C171,C172,C173,C174,C175,C176,C177,C178,C179,C180,C187,C203,C206,C224,C233,C235,C245,C762,C796,C797,C798,C800,C825,C826,C827,C828,C829,C830,C831,C832,C833,C834,C835,C836,C837,C838,C839,C840,C841,C842,C843,C844,C845,C846,C850,C859,C861,C862,C863,C865,C867,C868,C869,C870,C871,C872,C877,C878,C879,C880,C881,C882,C887,C888,C889,C890,C891,C892,C893,C894,C895,C896,C898,C901,C915,C1753,C1754,C1755,C1756,C1757,C1758,C1759,C1760,C1761,C1762,C1763,C1764,C1765,C1766,C1767,C1768,C1782,C1783,C1784,C1785,C1788,C1789,C1790,C1791,C1792,C1794,C1798,C1799,C1800,C1801,C1802,C1803,C1805,C1806,C1807,C1808,C1809,C1811,C1812,C1813,C1814,C1815,C1819,C1820,C1821,C1822,C1823,C1824,C1826,C1828,C1829,C1830,C1831,C1834,C1835,C1836,C1837,C1838,C1843,C1844,C1845,C1846,C1847,C1848,C1849,C1851,C1852,C1853,C1854,C1855,C1856,C1858,C1859,C1860,C1861,C1862,C1866,C1867,C1868,C1869,C1872,C1873,C1874,C1877,C1878,C1879,C1880,C1881,C1882,C1884,C1888,C1889,C1890,C1891,C1892,C1893,C1895,C1896,C1897,C1898,C1899,C1901,C1902,C1903,C1904,C1905,C1909,C1910,C1911,C1912,C1913,C1914,C1917,C1918,C1919,C1920,C1921,C1922,C1923,C1924,C1925,C1926,C1927,C1928,C1929,C1930,C1931,C1932,C1952,C1953,C1954,C1955,C1956,C1957,C1962,C1963,C1964,C1965,C1966,C1967,C1968,C1969,C1974,C1975,C1984,C1985,C1986,C1987,C1988,C1989,C1990,C1991,C1992,C1993,C1994,C1995,C1996,C1997,C1998,C1999 |  |  |  |  |  |  |
|  |  |  |  |  | 14 | 62011DF00-026-G |  | CAP,220nF,+/-10%,X7R,16V,G,SMD0402 | SAMSUNG SEMICONDUCTOR | CL05B224KO5NNNC |  | G |  |  |  |  |  |  |  |
|  |  |  |  |  | 14 | 62011DF00-023-G |  | CAP,220nF,+/-10%,X7R,16V,G,SMD0402 | TAIYO ELECTRIC IND.CO.LTD | EMK105B7224KV-FR |  | G |  |  |  |  |  |  |  |
| Multi | N |  | Y(3) | 15 | 15 | 62012GF00-015-G |  | CAP,22uF,+/-20%,X6S,6.3V,G,SMD0603 | MURATA ELEC. NORTH AMERICA | GRM188C80J226M | 16 | G | PSPC2,PIPC2,PFPC2,PEPC2,PSPC3,PIPC3,PFPC3,PEPC3,C158,C168,C874,C884,PSPC3000,PIPC3000,PFPC3000,PEPC3000 |  |  |  |  |  |  |
|  |  |  |  |  | 15 | 62012GF00-023-G |  | CAP,22uF,+/-20%,X6S,6.3V,G,SMD0603 | TAIYO ELECTRIC IND.CO.LTD | JDK107BC6226MA-T |  | G |  |  |  |  |  |  |  |
| Multi | N | ND | Y(3) | 16 | 16 | 62012H100-015-G |  | CAP,10uF,+/-20%,X6S,10V,G,SMD0603 | MURATA ELEC. NORTH AMERICA | GRM188C81A106M | 11 | G | PSTC16,PFRC16,C182,C225,C273,C812,C2147,C2148,C2149,C2150,C2151 |  |  |  |  |  |  |
|  |  |  |  |  | 16 | 62012H100-026-G |  | CAP,10uF,+/-20%,X6S,10V,G,SMD0603 | SAMSUNG SEMICONDUCTOR | CL10X106MP8NRNC |  | G |  |  |  |  |  |  |  |
|  |  |  |  |  | 16 | 62012H100-023-G |  | CAP,10uF,+/-20%,X6S,10V,G,SMD0603 | TAIYO ELECTRIC IND.CO.LTD | LMK107BC6106MA-T |  | G |  |  |  |  |  |  |  |
| Multi | Y | 2 | Y(3) | 17 | 17 | 620101T02-015-G |  | CAP,100nF,+/-10%,X7R,16V,G,SMD0402 | MURATA ELEC. NORTH AMERICA | GRM155R71C104K | 181 | G | PSPC1,PIPC1,PFPC1,PEPC1,PSTC10,PQPC10,PFRC10,PETC10,PERC10,PBNC16,PANC16,PBNC17,PANC17,PALC36,PALC41,PALC44,PBLC57,PBLC61,PBLC64,C192,C194,C196,C198,C316,C318,C320,C322,C440,C442,C444,C446,PBFC500,PBEC500,PAFC500,PAEC500,C564,C566,C568,C570,PBMC600,PBAC600,PAMC600,PAAC600,C908,C910,C912,C914,C1032,C1034,C1036,C1038,C1156,C1158,C1160,C1162,C1280,C1282,C1284,C1286,C1480,C1481,C1484,C1487,C1488,C1490,C1491,C1493,C1494,C1496,C1515,C1516,C1518,C1520,C1521,C1522,C1524,C1526,C1527,C1528,C1529,C1530,C1531,C1534,C1535,C1536,C1537,C1538,C1539,C1540,C1543,C1544,C1545,C1568,C1569,C1570,C1571,C1576,C1597,C1600,C1603,C1606,C1608,C1609,C1610,C1611,C1612,C1613,C1616,C1617,C1618,C1619,C1620,C1621,C1622,C1624,C1625,C1626,C1627,C1645,C1646,C1647,C1648,C1649,C1651,C1652,C1677,C1678,C1713,C1715,C1719,C1723,C1727,C1738,C1740,C1749,C1750,C1787,C1796,C1797,C1841,C1842,C1876,C1886,C1887,C1940,C1941,C1943,C1946,C1949,C1951,C1959,C1960,C1961,C1977,C1978,C1979,C1980,C1981,C1982,C1983,C2004,C2005,C2006,C2007,C2012,C2029,C2070,C2107,C2108,C2109,C2112,C2131,C2132,C2152,C2155,C2156,C2164,C2165,C2167,C2181,PSRC3016 |  |  |  |  |  |  |
|  |  |  |  |  | 17 | 620101T00-026-G |  | CAP,100nF,+/-10%,X7R,16V,G,SMD0402 | SAMSUNG SEMICONDUCTOR | CL05B104KO5NNNC |  | G |  |  |  |  |  |  |  |
|  |  |  |  |  | 17 | 620101T00-023-G |  | CAP,100nF,+/-10%,X7R,16V,G,SMD0402 | TAIYO ELECTRIC IND.CO.LTD | EMK105B7104KV-F |  | G |  |  |  |  |  |  |  |
| Multi | Y | ND | Y(3) | 18 | 18 | 62011KG00-015-G |  | CAP,100nF,+/-5%,X7R,10V,G,SMD0402 | MURATA ELEC. NORTH AMERICA | GRM155R71A104JA01D | 67 | G | C209,C210,C211,C212,C213,C214,C215,C216,C227,C333,C334,C335,C336,C337,C338,C339,C340,C457,C458,C459,C460,C461,C462,C463,C464,C581,C582,C583,C584,C585,C586,C587,C588,C925,C926,C927,C928,C929,C930,C931,C932,C1049,C1050,C1051,C1052,C1053,C1054,C1055,C1056,C1173,C1174,C1175,C1176,C1177,C1178,C1179,C1180,C1297,C1298,C1299,C1300,C1301,C1302,C1303,C1304,C1532,C2009 |  |  |  |  |  |  |
|  |  |  |  |  | 18 | 62011KG00-026-G |  | CAP,100nF,+/-5%,X7R,10V,G,SMD0402 | SAMSUNG SEMICONDUCTOR | CL05B104JP5NNNC |  | G |  |  |  |  |  |  |  |
| Multi | ND | ND | Y(1) | 19 | 19 | 620135Y00-015-G |  | CAP,2.2uF,+/-20%,X6S,10V,G,SMD0402 | MURATA ELEC. NORTH AMERICA | GRM155C81A225ME15D | 130 | G | PBNC9,PANC9,C237,C238,C239,C240,C247,C248,C249,C250,C265,C266,C267,C268,C283,C284,C285,C286,C361,C362,C363,C364,C371,C372,C373,C374,C389,C390,C391,C392,C407,C408,C409,C410,C485,C486,C487,C488,C495,C496,C497,C498,C513,C514,C515,C516,C531,C532,C533,C534,C609,C610,C611,C612,C619,C620,C621,C622,C637,C638,C639,C640,C655,C656,C657,C658,C953,C954,C955,C956,C963,C964,C965,C966,C981,C982,C983,C984,C999,C1000,C1001,C1002,C1077,C1078,C1079,C1080,C1087,C1088,C1089,C1090,C1105,C1106,C1107,C1108,C1123,C1124,C1125,C1126,C1201,C1202,C1203,C1204,C1211,C1212,C1213,C1214,C1229,C1230,C1231,C1232,C1247,C1248,C1249,C1250,C1325,C1326,C1327,C1328,C1335,C1336,C1337,C1338,C1353,C1354,C1355,C1356,C1371,C1372,C1373,C1374 |  |  |  |  |  |  |
|  |  |  |  |  | 19 | 620133P00-023-G |  | CAP,2.2uF,+/-20%,X6S,10V,G,SMD0402 | TAIYO ELECTRIC IND.CO.LTD | LMK105AC6225MV-F |  | G |  |  |  |  |  |  |  |
| Multi | ND | ND | Y(3) | 20 | 20 | 62010MU00-015-G |  | CAP,20pF,+/-5%,NPO(C0G),50V,G,SMD0402 | MURATA ELEC. NORTH AMERICA | GRM1555C1H200J | 2 | G | C1476,C1477 |  |  |  |  |  |  |
|  |  |  |  |  | 20 | 62010MU00-026-G |  | CAP,20pF,+/-5%,NPO(C0G),50V,G,SMD0402 | SAMSUNG SEMICONDUCTOR | CL05C200JB5NNNC |  | G |  |  |  |  |  |  |  |
| Multi | Y |  | Y(1) | 21 | 21 | 62010DW00-015-G |  | CAP,10uF,+/-10%,X7R,16V,G,SMD1206 | MURATA ELEC. NORTH AMERICA | GRM31CR71C106K | 11 | G | C1478,C1479,C1485,C1495,C1584,C1778,C1786,C1832,C1875,C1942,C2035 |  |  |  |  |  |  |
|  |  |  |  |  | 21 | 62010DW00-026-G |  | CAP,10uF,+/-10%,X7R,16V,G,SMD1206 | SAMSUNG SEMICONDUCTOR | CL31B106KOHNNNE |  | G |  |  |  |  |  |  |  |
|  |  |  |  |  | 21 | 62010DW00-023-G |  | CAP,10uF,+/-10%,X7R,16V,G,SMD1206 | TAIYO ELECTRIC IND.CO.LTD | EMK316B7106KL-TD |  | G |  |  |  |  |  |  |  |
| Multi | ND |  | Y(1) | 22 | 22 | 620115801-015-G |  | CAP,22uF,+/-10%,X7R,10V,G,SMD1206 | MURATA ELEC. NORTH AMERICA | GRM31CR71A226KE15L | 15 | G | C1486,C1489,C1492,C1774,C1775,C1793,C1795,C1839,C1840,C1883,C1885,C1938,C1939,C1950,C1976 |  |  |  |  |  |  |
|  |  |  |  |  | 22 | 620115800-023-G |  | CAP,22uF,+/-10%,X7R,10V,G,SMD1206 | TAIYO ELECTRIC IND.CO.LTD | LMK316B7226KL-TR |  | G |  |  |  |  |  |  |  |
|  |  |  |  |  | 22 | 620115800-026-G |  | CAP,22uF,+/-10%,X7R,10V,G,SMD1206 | SAMSUNG SEMICONDUCTOR | CL31B226KPHNNNE |  | G |  |  |  |  |  |  |  |
| Multi | ND | ND | Y(1) | 23 | 23 | 620109S00-015-G |  | CAP,4.7uF,+/-10%,X7R,10V,G,SMD0805 | MURATA ELEC. NORTH AMERICA | GRM21BR71A475K | 5 | G | C1499,C1533,C1577,C1585,C1596 |  |  |  |  |  |  |
|  |  |  |  |  | 23 | 620109S00-023-G |  | CAP,4.7uF,+/-10%,X7R,10V,G,SMD0805 | TAIYO ELECTRIC IND.CO.LTD | LMK212B7475KG-T |  | G |  |  |  |  |  |  |  |
|  |  |  |  |  | 23 | 620109S00-026-G |  | CAP,4.7uF,+/-10%,X7R,10V,G,SMD0805 | SAMSUNG SEMICONDUCTOR | CL21B475KPFNNNE |  | G |  |  |  |  |  |  |  |
| Multi | ND |  | Y(3) | 24 | 24 | 62010MF00-015-G |  | CAP,100pF,+/-10%,X7R,16V,G,SMD0201 | MURATA ELEC. NORTH AMERICA | GRM033R71C101K | 6 | G | C1502,C1592,C1598,C1601,C1604,C1607 |  |  |  |  |  |  |
|  |  |  |  |  | 24 | 62010MF00-023-G |  | CAP,100pF,+/-10%,X7R,16V,G,SMD0201 | TAIYO ELECTRIC IND.CO.LTD | EMK063B7101KP-F |  | G |  |  |  |  |  |  |  |
| Multi | ND | ND | Y(3) | 25 | 25 | 62010QB00-015-G |  | CAP,10nF,+/-10%,X7R,50V,G,SMD0402 | MURATA ELEC. NORTH AMERICA | GRM155R71H103K | 13 | G | PSIC7,C1541,C1679,C1680,C1681,C1682,C1684,C1685,C1686,C1688,C1704,C1710,C2069 |  |  |  |  |  |  |
|  |  |  |  |  | 25 | 62010QB00-026-G |  | CAP,10nF,+/-10%,X7R,50V,G,SMD0402 | SAMSUNG SEMICONDUCTOR | CL05B103KB5NNNC |  | G |  |  |  |  |  |  |  |
|  |  |  |  |  | 25 | 62010QB00-023-G |  | CAP,10nF,+/-10%,X7R,50V,G,SMD0402 | TAIYO ELECTRIC IND.CO.LTD | UMK105B7103KV-F |  | G |  |  |  |  |  |  |  |
| Multi | Y | 2 | Y(3) | 26 | 26 | 62010GW00-015-G |  | CAP,10pF,+/-5%,NPO,50V,G,SMD0402 | MURATA ELEC. NORTH AMERICA | GRM1555C1H100J | 1 | G | C1542 |  |  |  |  |  |  |
|  |  |  |  |  | 26 | 620102D00-026-G |  | CAP,10pF,+/-5%,NPO,50V,G,SMD0402 | SAMSUNG SEMICONDUCTOR | CL05C100JB5NNNC |  | G |  |  |  |  |  |  |  |
| Multi | Y | 2 | Y(1) | 27 | 27 | 620109200-015-G |  | CAP,10uF,+/-10%,X7R,6.3V,G,SMD0805 | MURATA ELEC. NORTH AMERICA | GRM21BR70J106K | 2 | G | C1623,C1747 |  |  |  |  |  |  |
|  |  |  |  |  | 27 | 620109200-023-G |  | CAP,10uF,+/-10%,X7R,6.3V,G,SMD0805 | TAIYO ELECTRIC IND.CO.LTD | JMK212B7106KG-T |  | G |  |  |  |  |  |  |  |
|  |  |  |  |  | 27 | 620109200-026-G |  | CAP,10uF,+/-10%,X7R,6.3V,G,SMD0805 | SAMSUNG SEMICONDUCTOR | CL21B106KQQNNNE |  | G |  |  |  |  |  |  |  |
| Multi | Y | 2 | Y(3) | 28 | 28 | 620102S00-015-G |  | CAP,33pF,+/-5%,NPO(C0G),50V,G,SMD0402 | MURATA ELEC. NORTH AMERICA | GRM1555C1H330J | 11 | G | PUAC3,PSAC3,PRAC3,PQAC3,PPAC3,PIAC3,PFAC3,PEAC3,C1653,C1654,C2146 |  |  |  |  |  |  |
|  |  |  |  |  | 28 | 620102S00-023-G |  | CAP,33pF,+/-5%,NPO(C0G),50V,G,SMD0402 | TAIYO ELECTRIC IND.CO.LTD | UMK105CG330JV-F |  | G |  |  |  |  |  |  |  |
|  |  |  |  |  | 28 | 620102S00-026-G |  | CAP,33pF,+/-5%,NPO(C0G),50V,G,SMD0402 | SAMSUNG SEMICONDUCTOR | CL05C330JB5NNNC |  | G |  |  |  |  |  |  |  |
| Multi | ND | ND | Y(3) | 29 | 29 | 62010K200-015-G |  | CAP,12pF,+/-5%,NPO(C0G),50V,G,SMD0402 | MURATA ELEC. NORTH AMERICA | GRM1555C1H120J | 2 | G | C1655,C1656 |  |  |  |  |  |  |
|  |  |  |  |  | 29 | 62010K200-023-G |  | CAP,12pF,+/-5%,NPO(C0G),50V,G,SMD0402 | TAIYO ELECTRIC IND.CO.LTD | UMK105CG120JV-F |  | G |  |  |  |  |  |  |  |
|  |  |  |  |  | 29 | 62010K200-026-G |  | CAP,12pF,+/-5%,NPO(C0G),50V,G,SMD0402 | SAMSUNG SEMICONDUCTOR | CL05C120JB5NNNC |  | G |  |  |  |  |  |  |  |
| Multi | ND | ND | Y(3) | 30 | 30 | 620100L00-015-G |  | CAP,22pF,+/-5%,NPO(C0G),50V,G,SMD0402 | MURATA ELEC. NORTH AMERICA | GRM1555C1H220J | 16 | G | C1657,C1658,C1659,C1660,C1661,C1662,C1663,C1664,C1665,C1666,C1668,C1669,C2014,C2016,C2018,C2020 |  |  |  |  |  |  |
|  |  |  |  |  | 30 | 620100L00-023-G |  | CAP,22pF,+/-5%,NPO(C0G),50V,G,SMD0402 | TAIYO ELECTRIC IND.CO.LTD | UMK105CG220JV-F |  | G |  |  |  |  |  |  |  |
|  |  |  |  |  | 30 | 620100L00-026-G |  | CAP,22pF,+/-5%,NPO(C0G),50V,G,SMD0402 | SAMSUNG SEMICONDUCTOR | CL05C220JB5NNNC |  | G |  |  |  |  |  |  |  |
| Multi | ND |  | N | 31 | 31 | 620109N00-015-G |  | CAP,2.2uF,+/-10%,X7R,10V,G,SMD0603 | MURATA ELEC. NORTH AMERICA | GRM188R71A225K | 8 | G | C1683,C1687,C1703,C1709,C1717,C1721,C1725,C1729 |  |  |  |  |  |  |
|  |  |  |  |  | 31 | 620109N00-023-G |  | CAP,2.2uF,+/-10%,X7R,10V,G,SMD0603 | TAIYO ELECTRIC IND.CO.LTD | LMK107B7225KA-T |  | G |  |  |  |  |  |  |  |
|  |  |  |  |  | 31 | 620109N00-026-G |  | CAP,2.2uF,+/-10%,X7R,10V,G,SMD0603 | SAMSUNG SEMICONDUCTOR | CL10B225KP8NNNC |  | G |  |  |  |  |  |  |  |
| Multi | ND | ND | Y(1) | 32 | 32 | 62012A400-015-G |  | CAP,100nF,+/-10%,X7R,25V,G,SMD0402 | MURATA ELEC. NORTH AMERICA | GRM155R71E104KE14D | 88 | G | PSTC1,PSLC1,PSFC1,PSEC1,PSDC1,PQPC1,PFRC1,PEEC1,PEDC1,PSUC3,PSTC6,PSLC6,PSFC6,PSEC6,PSDC6,PQPC6,PFRC6,PEEC6,PEDC6,PANC6,PBNC7,PBMC10,PBFC10,PBEC10,PBAC10,PAMC10,PAFC10,PAEC10,PAAC10,PSIC21,PETC21,PERC21,PBFC58,PBEC58,PAFC58,PAEC58,PBMC59,PAMC59,PBAC123,PAAC123,C1689,C1695,C1696,C1697,C1698,C1705,C1711,C1770,C1771,C1772,C1773,C1776,C1777,C1779,C1810,C1816,C1817,C1818,C1857,C1863,C1864,C1865,C1900,C1906,C1907,C1908,C1934,C1935,C1936,C1937,C1944,C1945,C1971,C1972,C1973,C2030,C2031,PSPC3002,PIPC3002,PFPC3002,PEPC3002,PSRC3006,PSPC3008,PIPC3008,PFPC3008,PEPC3008,PSRC3009,PSRC3011 |  |  |  |  |  |  |
|  |  |  |  |  | 32 | 62012A400-023-G |  | CAP,100nF,+/-10%,X7R,25V,G,SMD0402 | TAIYO ELECTRIC IND.CO.LTD | TMK105B7104KV-FR |  | G |  |  |  |  |  |  |  |
|  |  |  |  |  | 32 | 62012A400-026-G |  | CAP,100nF,+/-10%,X7R,25V,G,SMD0402 | SAMSUNG SEMICONDUCTOR | CL05B104KA5NNNC |  | G |  |  |  |  |  |  |  |
| Multi | Y | 2 | Y(3) | 33 | 33 | 620103K00-015-G |  | CAP,1nF,+/-10%,X7R,50V,G,SMD0402 | MURATA ELEC. NORTH AMERICA | GRM155R71H102K | 16 | G | PHAC2,PUAC7,PSAC7,PRAC7,PQAC7,PPAC7,PIAC7,PFAC7,PEAC7,PBMC60,PAMC60,PBAC124,PAAC124,C1690,C1706,C1712 |  |  |  |  |  |  |
|  |  |  |  |  | 33 | 620103K00-026-G |  | CAP,1nF,+/-10%,X7R,50V,G,SMD0402 | SAMSUNG SEMICONDUCTOR | CL05B102KB5NNNC |  | G |  |  |  |  |  |  |  |
|  |  |  |  |  | 33 | 620103K00-023-G |  | CAP,1nF,+/-10%,X7R,50V,G,SMD0402 | TAIYO ELECTRIC IND.CO.LTD | UMK105B7102KV-F |  | G |  |  |  |  |  |  |  |
| Single | Y | 2 | Y(3) | 34 | 34 | 620107600-015-G |  | CAP,27pF,+/-5%,NPO(C0G),50V,G,SMD0402 | MURATA ELEC. NORTH AMERICA | GRM1555C1H270J | 2 | G | C1707,C1708 |  |  |  |  |  |  |
| Multi | Y | 2 | Y(3) | 35 | 35 | 620112900-015-G |  | CAP,47nF,+/-10%,X7R,25V,G,SMD0402 | MURATA ELEC. NORTH AMERICA | GRM155R71E473K | 4 | G | C1734,C1735,C1736,C1739 |  |  |  |  |  |  |
|  |  |  |  |  | 35 | 620112900-026-G |  | CAP,47nF,+/-10%,X7R,25V,G,SMD0402 | SAMSUNG SEMICONDUCTOR | CL05B473KA5NNNC |  | G |  |  |  |  |  |  |  |
|  |  |  |  |  | 35 | 620112900-023-G |  | CAP,47nF,+/-10%,X7R,25V,G,SMD0402 | TAIYO ELECTRIC IND.CO.LTD | TMK105B7473KV-F |  | G |  |  |  |  |  |  |  |
| Multi | Y | 2 | Y(3) | 36 | 36 | 620103U00-015-G |  | CAP,470pF,+/-10%,X7R,50V,G,SMD0402 | MURATA ELEC. NORTH AMERICA | GRM155R71H471K | 14 | G | PBMC3,PBFC3,PBEC3,PBAC3,PAMC3,PAFC3,PAEC3,PAAC3,PALC42,PALC43,PBLC58,PBLC59,C1737,C1741 |  |  |  |  |  |  |
|  |  |  |  |  | 36 | 620103U00-026-G |  | CAP,470pF,+/-10%,X7R,50V,G,SMD0402 | SAMSUNG SEMICONDUCTOR | CL05B471KB5NNNC |  | G |  |  |  |  |  |  |  |
|  |  |  |  |  | 36 | 620103U00-023-G |  | CAP,470pF,+/-10%,X7R,50V,G,SMD0402 | TAIYO ELECTRIC IND.CO.LTD | UMK105B7471KV-F |  | G |  |  |  |  |  |  |  |
| Multi | Y | 2 | Y(1) | 37 | 37 | 62011D900-015-G |  | CAP,22uF,+/-10%,X7R,6.3V,G,SMD1206 | MURATA ELEC. NORTH AMERICA | GRM31CR70J226K | 1 | G | C1746 |  |  |  |  |  |  |
|  |  |  |  |  | 37 | 62011D900-023-G |  | CAP,22uF,+/-10%,X7R,6.3V,G,SMD1206 | TAIYO ELECTRIC IND.CO.LTD | JMK316B7226KL-T |  | G |  |  |  |  |  |  |  |
|  |  |  |  |  | 37 | 62011D900-026-G |  | CAP,22uF,+/-10%,X7R,6.3V,G,SMD1206 | SAMSUNG SEMICONDUCTOR | CL31B226KQHNNNE |  | G |  |  |  |  |  |  |  |
| Multi | ND | ND | Y(1) | 38 | 38 | 62011HS01-015-G |  | CAP,10uF,+/-10%,X7R,25V,G,SMD1206 | MURATA ELEC. NORTH AMERICA | GRM31CR71E106K | 8 | G | C1769,C1804,C1850,C1894,C1933,C1958,C1970,C2032 |  |  |  |  |  |  |
|  |  |  |  |  | 38 | 62011HS00-026-G |  | CAP,10uF,+/-10%,X7R,25V,G,SMD1206 | SAMSUNG SEMICONDUCTOR | CL31B106KAHNNNE |  | G |  |  |  |  |  |  |  |
|  |  |  |  |  | 38 | 62011HS00-023-G |  | CAP,10uF,+/-10%,X7R,25V,G,SMD1206 | TAIYO ELECTRIC IND.CO.LTD | TMK316B7106KL-TD |  | G |  |  |  |  |  |  |  |
| Multi | Y |  | Y(1) | 39 | 39 | 620130V00-015-G |  | CAP,10uF,+/-20%,X6S,16V,G,SMD0603 | MURATA ELEC. NORTH AMERICA | GRM188C81C106MA73D | 9 | G | PBNC1,PANC8,PQPC16,C2013,C2015,C2017,C2019,C2188,PSRC3008 |  |  |  |  |  |  |
|  |  |  |  |  | 39 | 620130V00-023-G |  | CAP,10uF,+/-20%,X6S,16V,G,SMD0603 | TAIYO ELECTRIC IND.CO.LTD | EMK107BC6106MA-T |  | G |  |  |  |  |  |  |  |
|  |  |  |  |  | 39 | 620130V00-026-G |  | CAP,10uF,+/-20%,X6S,16V,G,SMD0603 | SAMSUNG SEMICONDUCTOR | CL10X106MO8NRNC |  | G |  |  |  |  |  |  |  |
| Multi | Y | 2 | ND | 40 | 40 | 620108000-015-G |  | CAP,100pF,+/-5%,NPO(C0G),50V,G,SMD0402 | MURATA ELEC. NORTH AMERICA | GRM1555C1H101J | 22 | G | PSPC4,PIPC4,PFPC4,PEPC4,PBAC4,PAAC4,PSRC9,PBNC12,PANC12,PSLC14,PSFC14,PSEC14,PSDC14,PEEC14,PEDC14,PBNC14,PANC14,PSIC20,PETC20,PERC20,C2041,C2114 |  |  |  |  |  |  |
|  |  |  |  |  | 40 | 620108000-026-G |  | CAP,100pF,+/-5%,NPO(C0G),50V,G,SMD0402 | SAMSUNG SEMICONDUCTOR | CL05C101JB5NNNC |  | G |  |  |  |  |  |  |  |
|  |  |  |  |  | 40 | 620108000-023-G |  | CAP,100pF,+/-5%,NPO(C0G),50V,G,SMD0402 | TAIYO ELECTRIC IND.CO.LTD | UMK105CG101JV-F |  | G |  |  |  |  |  |  |  |
| Multi | Y | 2 | Y(3) | 41 | 41 | 62010G800-015-G |  | CAP,22nF,+/-10%,X7R,16V,G,SMD0402 | MURATA ELEC. NORTH AMERICA | GRM155R71C223K | 3 | G | PHAC4,C2063,C2129 |  |  |  |  |  |  |
|  |  |  |  |  | 41 | 62010G800-026-G |  | CAP,22nF,+/-10%,X7R,16V,G,SMD0402 | SAMSUNG SEMICONDUCTOR | CL05B223KO5NNNC |  | G |  |  |  |  |  |  |  |
|  |  |  |  |  | 41 | 62010G800-023-G |  | CAP,22nF,+/-10%,X7R,16V,G,SMD0402 | TAIYO ELECTRIC IND.CO.LTD | EMK105B7223KV-F |  | G |  |  |  |  |  |  |  |
| Multi | ND | ND | Y(3) | 42 | 42 | 620110V00-015-G |  | CAP,1.2nF,+/-10%,X7R,50V,G,SMD0402 | MURATA ELEC. NORTH AMERICA | GRM155R71H122K | 1 | G | C2066 |  |  |  |  |  |  |
|  |  |  |  |  | 42 | 620110V00-026-G |  | CAP,1.2nF,+/-10%,X7R,50V,G,SMD0402 | SAMSUNG SEMICONDUCTOR | CL05B122KB5NNNC |  | G |  |  |  |  |  |  |  |
|  |  |  |  |  | 42 | 620110V00-023-G |  | CAP,1.2nF,+/-10%,X7R,50V,G,SMD0402 | TAIYO ELECTRIC IND.CO.LTD | UMK105B7122KV-F |  | G |  |  |  |  |  |  |  |
| Sole | ND | ND | Y(1) | 43 | 43 | 62012TW00-015-G |  | CAP,470nF,+/-10%,X7R,16V,G,SMD0402 | MURATA ELEC. NORTH AMERICA | GRM155R71C474KE01D | 2 | G | C2081,C2082 |  |  |  |  |  |  |
| Multi | ND |  | Y(1) | 44 | 44 | 62012PS00-015-G |  | CAP,10uF,+/-20%,X6S,4V,G,SMD0402 | MURATA ELEC. NORTH AMERICA | GRM155C80G106M | 495 | G | PBFC28,PBEC28,PAFC28,PAEC28,PBMC29,PBFC29,PBEC29,PBAC29,PAMC29,PAFC29,PAEC29,PAAC29,PBMC30,PBFC30,PBEC30,PBAC30,PAMC30,PAFC30,PAEC30,PAAC30,PBMC31,PBFC31,PBEC31,PBAC31,PAMC31,PAFC31,PAEC31,PAAC31,PBMC32,PBFC32,PBEC32,PBAC32,PAMC32,PAFC32,PAEC32,PAAC32,PBMC33,PBFC33,PBEC33,PBAC33,PAMC33,PAFC33,PAEC33,PAAC33,PBMC34,PBFC34,PBEC34,PBAC34,PAMC34,PAFC34,PAEC34,PAAC34,PBMC35,PBFC35,PBEC35,PBAC35,PAMC35,PAFC35,PAEC35,PAAC35,PBMC36,PBFC36,PBEC36,PBAC36,PAMC36,PAFC36,PAEC36,PAAC36,PBMC37,PBFC37,PBEC37,PBAC37,PAMC37,PAFC37,PAEC37,PAAC37,PBMC38,PBFC38,PBEC38,PBAC38,PAMC38,PAFC38,PAEC38,PAAC38,PBMC39,PBFC39,PBEC39,PBAC39,PAMC39,PAFC39,PAEC39,PAAC39,PBMC40,PBFC40,PBEC40,PBAC40,PAMC40,PAFC40,PAEC40,PAAC40,PBMC41,PBFC41,PBEC41,PBAC41,PAMC41,PAFC41,PAEC41,PAAC41,PBMC42,PBFC42,PBEC42,PBAC42,PAMC42,PAFC42,PAEC42,PAAC42,PBMC43,PBFC43,PBEC43,PBAC43,PAMC43,PAFC43,PAEC43,PAAC43,PBMC44,PBFC44,PBEC44,PBAC44,PAMC44,PAFC44,PAEC44,PAAC44,PBMC45,PBFC45,PBEC45,PBAC45,PAMC45,PAFC45,PAEC45,PAAC45,PBMC46,PBFC46,PBEC46,PBAC46,PAMC46,PAFC46,PAEC46,PAAC46,PBMC47,PBFC47,PBEC47,PBAC47,PAMC47,PAFC47,PAEC47,PAAC47,PBMC48,PBFC48,PBEC48,PBAC48,PAMC48,PAFC48,PAEC48,PAAC48,PBMC49,PBFC49,PBEC49,PBAC49,PAMC49,PAFC49,PAEC49,PAAC49,PBMC50,PBFC50,PBEC50,PBAC50,PAMC50,PAFC50,PAEC50,PAAC50,PBMC51,PBFC51,PBEC51,PBAC51,PAMC51,PAFC51,PAEC51,PAAC51,PBMC52,PBFC52,PBEC52,PBAC52,PAMC52,PAFC52,PAEC52,PAAC52,PBMC53,PBFC53,PBEC53,PBAC53,PAMC53,PAFC53,PAEC53,PAAC53,PBMC54,PBFC54,PBEC54,PBAC54,PAMC54,PAFC54,PAEC54,PAAC54,PBMC55,PBFC55,PBEC55,PBAC55,PAMC55,PAFC55,PAEC55,PAAC55,PBMC56,PBFC56,PBEC56,PBAC56,PAMC56,PAFC56,PAEC56,PAAC56,PBMC57,PBFC57,PBEC57,PBAC57,PAMC57,PAFC57,PAEC57,PAAC57,PBMC58,PBAC58,PAMC58,PAAC58,PBAC59,PAAC59,PBAC60,PAAC60,PBAC61,PAAC61,PBFC62,PBEC62,PBAC62,PAFC62,PAEC62,PAAC62,PBMC63,PBFC63,PBEC63,PBAC63,PAMC63,PAFC63,PAEC63,PAAC63,PBMC64,PBFC64,PBEC64,PBAC64,PAMC64,PAFC64,PAEC64,PAAC64,PBMC65,PBFC65,PBEC65,PBAC65,PAMC65,PAFC65,PAEC65,PAAC65,PBMC66,PBFC66,PBEC66,PBAC66,PAMC66,PAFC66,PAEC66,PAAC66,PBMC67,PBFC67,PBEC67,PBAC67,PAMC67,PAFC67,PAEC67,PAAC67,PBMC68,PBFC68,PBEC68,PBAC68,PAMC68,PAFC68,PAEC68,PAAC68,PBMC69,PBFC69,PBEC69,PBAC69,PAMC69,PAFC69,PAEC69,PAAC69,PBMC70,PBFC70,PBEC70,PBAC70,PAMC70,PAFC70,PAEC70,PAAC70,PBMC71,PBFC71,PBEC71,PBAC71,PAMC71,PAFC71,PAEC71,PAAC71,PBMC72,PBAC72,PAMC72,PAAC72,PBAC73,PAAC73,PBAC74,PAAC74,PBAC75,PAAC75,PBAC76,PAAC76,PBAC77,PAAC77,PBAC78,PAAC78,PBAC81,PAAC81,PBAC82,PAAC82,PBAC83,PAAC83,PBAC84,PAAC84,PBAC85,PAAC85,PBAC86,PAAC86,PBAC87,PAAC87,PBAC88,PAAC88,PBAC89,PAAC89,PBAC90,PAAC90,PBAC91,PAAC91,PBAC92,PAAC92,PBAC93,PAAC93,PBAC94,PAAC94,PBAC95,PAAC95,PBAC96,PAAC96,PBAC97,PAAC97,PBAC98,PAAC98,PBAC99,PAAC99,PBAC100,PAAC100,PBAC101,PAAC101,PBAC102,PAAC102,PBAC103,PAAC103,PBAC104,PAAC104,PBAC105,PAAC105,PBAC106,PAAC106,PBAC107,PAAC107,PBAC108,PAAC108,PBAC109,PAAC109,PBAC110,PAAC110,PBAC113,PAAC113,PBAC114,PAAC114,PBAC115,PAAC115,PBAC116,PAAC116,PBAC117,PAAC117,PBAC118,PAAC118,PBAC119,PAAC119,PBAC120,PAAC120,PBAC121,PAAC121,PBAC122,PAAC122,PBAC127,PAAC127,PBAC128,PAAC128,PBAC129,PAAC129,PBAC130,PAAC130,PBAC131,PAAC131,PBAC132,PAAC132,PBAC133,PAAC133,PBAC134,PAAC134,PBAC135,PAAC135,PBAC136,PAAC136,PBAC137,PAAC137,PBAC138,PAAC138,PBAC139,PAAC139,PBAC140,PAAC140,PBAC141,PAAC141,PBAC142,PAAC142,PBAC143,PAAC143,PBAC144,PAAC144,PBAC145,PAAC145,PBAC146,PAAC146,PBAC147,PAAC147,PBAC148,PAAC148,PBAC149,PAAC149,PBAC150,PAAC150,PBAC151,PAAC151,PBAC152,PAAC152,PBAC153,PAAC153,PBAC154,PAAC154,PBAC155,PAAC155,PBAC156,PAAC156,PBFC501,PBEC501,PAFC501,PAEC501,C2168,C2169,C2170,C2172,C2173,C2174,C2175,C2176,C2177,C2178,C2179 |  |  |  |  |  |  |
|  |  |  |  |  | 44 | 62012PS00-023-G |  | CAP,10uF,+/-20%,X6S,4V,G,SMD0402 | TAIYO ELECTRIC IND.CO.LTD | AMK105CC6106MV-F |  | G |  |  |  |  |  |  |  |
|  |  |  |  |  | 44 | 62012PS00-026-G |  | CAP,10uF,+/-20%,X6S,4V,G,SMD0402 | SAMSUNG SEMICONDUCTOR | CL05X106MR5NUNC |  | G |  |  |  |  |  |  |  |
| Multi | ND | ND | N | 45 | 45 | 521803M00-227-G |  | Diode,Array-TVS,UCLAMP0508T.TCT,Level 4,5V,G,SLP,SMD-9 | SEMTECH CORPORATION. | UCLAMP0508T.TCT | 1 | G | DN1 |  |  |  |  |  |  |
|  |  |  |  |  | 45 | 521802K00-223-G |  | Diode,Array-TVS,NUP8011MUTAG,UDFN,9P,G | ON SEMICONDUCTOR CORP | NUP8011MUTAG |  | G |  |  |  |  |  |  |  |
| Multi |  |  | N | 46 | 46 | 520300A00-237-G |  | DIODE,Schottky,SD103AW-7-F,40V,0.35A,G,SOD123-2,SMD | DIODES INEORPORATION | SD103AW-7-F | 1 | G | D19 |  |  |  |  |  |  |
|  |  |  |  |  | 46 | 520302L00-223-G |  | Diode,Schottky,MBR0540T1G,40V,500mA,SOD-123,2P,G | ON SEMICONDUCTOR CORP | MBR0540T1G |  | G |  |  |  |  |  |  |  |
| Multi | ND | ND | N | 47 | 47 | 520100200-237-G |  | DIODE,Switching,1N4148W-7-F,100V,0.15A,G,SOD123-2,SMD | DIODES INEORPORATION | 1N4148W-7-F | 7 | G | PHAD6,D20,D21,D29,D30,D31,D32 |  |  |  |  |  |  |
|  |  |  |  |  | 47 | 520102P00-031-G |  | DIODE,Switching,BAS16H,100V,0.5A,G,SOD123F-2,SMD | NXP SEMICONDUCTORS | BAS16H |  | G |  |  |  |  |  |  |  |
| Multi | ND |  | N | 48 | 48 | 520308A00-237-G |  | Diode,Schottky,B0530WS-7-F,30V,500mA,G,SOD-323-2,SMD | DIODES INCORPORATION | B0530WS-7-F | 6 | G | D22,D23,D24,D25,D26,D27 |  |  |  |  |  |  |
|  |  |  |  |  | 48 | 520309600-031-G |  | Diode,Schottky,PMEG3005AEA,30V,500mA,SOD-323,2P,G | NXP SEMICONDUCTORS | PMEG3005AEA |  | G |  |  |  |  |  |  |  |
| Multi | ND |  | N | 49 | 49 | 52010MP00-237-G |  | Diode,Rectifier,ES2D-13-F,200V,2A,G,SMB-2,SMD | DIODES INCORPORATION | ES2D-13-F | 3 | G | D28,D35,D36 |  |  |  |  |  |  |
|  |  |  |  |  | 49 | 52010N000-223-G |  | Diode,Rectifier&Switching,MURS220T3G,200V,2A,SMB/DO-214AA,2P,G | ON SEMICONDUCTOR CORP | MURS220T3G |  | G |  |  |  |  |  |  |  |
| Multi | ND |  | N | 50 | 50 | 520308D00-237-G |  | DIODE,Schottky Rectifier,1N5819HW-7-F,40V,1A,G,SOD123-2,SMD | DIODES INCORPORATION | 1N5819HW-7-F | 1 | G | D33 |  |  |  |  |  |  |
|  |  |  |  |  | 50 | 52030P100-223-G |  | Diode,Schottky,MBR140SFT1G,40V,1A,SOD-123FL,2P,G | ON SEMICONDUCTOR CORP | MBR140SFT1G |  | G |  |  |  |  |  |  |  |
|  |  |  |  |  | 50 | 520318S00-223-G |  | Diode,Schottky,MBR140SFT3G,40V,1A,SOD-123FL,2P,G | ON SEMICONDUCTOR CORP | MBR140SFT3G |  | G |  |  |  |  |  |  |  |
| Multi | ND | ND | N | 51 | 51 | 520401Y00-237-G |  | DIODE,Zener,BZT52C3V6-7-F,3.6V,5mA,G,SOD123-2,SMD | DIODES INEORPORATION | BZT52C3V6-7-F | 1 | G | D34 |  |  |  |  |  |  |
|  |  |  |  |  | 51 | 520407600-223-G |  | Diode,ZENER,MMSZ3V6T1G,3.6V,5mA,SOD-123,2P,G | ON SEMICONDUCTOR CORP | MMSZ3V6T1G |  | G |  |  |  |  |  |  |  |
| Multi | Y | 1 | N | 52 | 52 | 520304B00-237-G |  | DIODE,Schottky,BAT54WS-7-F,30V,0.1A,G,SOD323-2,SMD | DIODES INEORPORATION | BAT54WS-7-F | 3 | G | D53,D54,D56 |  |  |  |  |  |  |
|  |  |  |  |  | 52 | 520303500-223-G |  | Diode,Schottky,BAT54HT1G,30V,200mA,SOD-323,2P,G | ON SEMICONDUCTOR CORP | BAT54HT1G |  | G |  |  |  |  |  |  |  |
|  |  |  |  |  | 52 | 520308200-031-G |  | DIODE,Schottky,1PS76SB10,30V,200mA,G,SOD323-2,SMD | NXP SEMICONDUCTORS | 1PS76SB10 |  | G |  |  |  |  |  |  |  |
| Multi | ND | ND | N | 53 | 53 | 52030NP00-185-G |  | DIODE,Schottky,RB521S30,30V,200mA,G,SOD523-2,SMD | FAIRCHILD SEMICONDUCTOR CORP | RB521S30 | 1 | G | D57 |  |  |  |  |  |  |
|  |  |  |  |  | 53 | 52030NP00-031-G |  | Diode,Schottky,RB521S30,30V,200mA,SOD-523,2P,G | NXP SEMICONDUCTORS | RB521S30 |  | G |  |  |  |  |  |  |  |
|  |  |  |  |  | 53 | 52030AG00-237-G |  | Diode,Schottky,SDM20U30-7,30V,200mA,SOD-523,2P,G | DIODES INCORPORATION | SDM20U30-7 |  | G |  |  |  |  |  |  |  |
| Single | Y |  | N | 54 | 54 | 52180BC00-223-G |  | DIODE,Array-TVS,ESD8004MUTAG,G,UDFN-10,SMD | ON SEMICONDUCTOR CORP | ESD8004MUTAG | 1 | G | ED1 |  |  |  |  |  |  |
| Multi | ND |  | N | 55 | 55 | 521800900-227-G |  | DIODE,Array-TVS,SRV05-4.TCT,5V,12A,G,SOT23-6,SMD | SEMTECH CORPORATION. | SRV05-4.TCT | 2 | G | ED2,ED3 |  |  |  |  |  |  |
|  |  |  |  |  | 55 | 52180C200-086-G |  | Diode,Array-TVS,SRV05-4HTG,SOT-23,6P,G | LITTELFUSE FAR EAST PTE LTD | SRV05-4HTG |  | G |  |  |  |  |  |  |  |
| Multi | N | ND | Y(2) | 56 | 56 | 720101900-015-G |  | FB,60 Ohm@100MHz,+/-25%,3A,25mOhm,G,SMD0805 | MURATA ELEC. NORTH AMERICA | BLM21PG600SN1D | 1 | G | FB1 |  |  |  |  |  |  |
|  |  |  |  |  | 56 | 720101900-026-G |  | FB,60 Ohm@100MHz,+/-25%,3A,25mOhm,G,SMD0805 | SAMSUNG SEMICONDUCTOR | CIC21P600NE |  | G |  |  |  |  |  |  |  |
| Multi | N | ND | Y(1) | 57 | 57 | 720406E00-015-G |  | Common Choke,90Ohm@100MHz,+/-25%,220mA,G,SMD0805 | MURATA ELEC. NORTH AMERICA | DLW21HN900HQ2L | 3 | G | FL1,FL4,FL10 |  |  |  |  |  |  |
|  |  |  |  |  | 57 | 720405D00-016-G |  | Common Choke,90 Ohm@100MHz,Type,200mA,G,SMD0805 | TDK ELECTRONICS EUROPE GMBH | ACM2012E-900-2P-T01 |  | G |  |  |  |  |  |  |  |
|  |  |  |  |  | 57 | 720402300-129-G |  | Common Choke,90 Ohm@100MHz,Type,200mA,G,SMD0805 | MAG.LAYERS, SCIENTIFIC-TECHNICS (KUNSHAN) CO., LTD. | MCI-2012H-900 |  | G |  |  |  |  |  |  |  |
| Multi | ND | ND | Y(1) | 58 | 58 | 720400201-015-G |  | Filter,Common Mode,90Ohm@100MHz,+/-25%,330mA,G,SMD0805 | MURATA ELEC. NORTH AMERICA | DLW21HN900SQ2L | 7 | G | FL2,FL3,FL5,FL6,FL7,FL8,FL9 |  |  |  |  |  |  |
|  |  |  |  |  | 58 | 720400M00-059-G |  | Common Choke,90 Ohm@100MHz,+/-25%,400mA,G,SMD0805 | TAI-TECH ADVANCED ELECTRONICS CO., LTD. | WCM2012F2SF-900T04 |  | G |  |  |  |  |  |  |  |
|  |  |  |  |  | 58 | 720400800-016-G |  | Common Choke,90 Ohm@100MHz,+/-25%,400mA,190mOhm,2L,G,SMD0805 | TDK ELECTRONICS EUROPE GMBH | ACM2012-900-2P-T |  | G |  |  |  |  |  |  |  |
| Sole | ND |  | Y(1) | 59 | 59 | 730100400-086-G |  | Fuse,Very fast acting,3A,32V,G,SMD0603 | LITTELFUSE FAR EAST PTE LTD | 0467003.NR | 2 | G | FS2,FS3 |  |  |  |  |  |  |
| Multi | ND |  | Y(1) | 60 | 60 | 730102701-086-G |  | Fuse,Fast acting,32V,7A,G,SMD1206 | LITTELFUSE FAR EAST PTE LTD | 0440007.WR | 6 | G | FS4,FS9,FS12,FS15,FS16,FS21 |  |  |  |  |  |  |
|  |  |  |  |  | 60 | 730102704-088-G |  | Fuse,Fast acting,32V,7A,G,SMD1206 | COOPER BUSSMANN, INC. | CC12H7A-TR |  | G |  |  |  |  |  |  |  |
| Multi | ND |  | Y(1) | 61 | 61 | 0438005.WRGT |  | Fuse,Fast acting,32V,5A,G,SMD0603 | LITTELFUSE FAR EAST PTE LTD | 0438005.WRGT | 11 | G | FS5,FS8,FS11,FS14,FS17,FS19,FS20,FS23,FS24,FS25,FS26 |  |  |  |  |  |  |
|  |  |  |  |  | 61 | 730103M00-086-G |  | Fuse,Fast acting,32V,5A,G,SMD0603 | LITTELFUSE FAR EAST PTE LTD | 0438005.WR |  | G |  |  |  |  |  |  |  |
|  |  |  |  |  | 61 | 730103M00-088-G |  | Fuse,Fast acting,32V,5A,SMD0603,G | COOPER BUSSMANN, INC. | CC06H5A-TR |  | G |  |  |  |  |  |  |  |
| Multi | ND | ND | Y(1) | 62 | 62 | 730102B01-086-G |  | Fuse,Fast acting,32V,1A,G,SMD0603 | LITTELFUSE FAR EAST PTE LTD | 0438001.WR | 5 | G | FS6,FS7,FS10,FS13,FS18 |  |  |  |  |  |  |
|  |  |  |  |  | 62 | 730102B03-088-G |  | Fuse,Fast acting,32V,1A,SMD0603,G | COOPER BUSSMANN, INC. | CC06H1A-TR |  | G |  |  |  |  |  |  |  |
| Sole | N |  | Y(1) | 63 | 63 | 730102000-086-G |  | Fuse,Fast acting,24V,10A,G,SMD1206 | LITTELFUSE FAR EAST PTE LTD | 0501010.WR | 1 | G | FS22 |  |  |  |  |  |  |
| Sole | ND |  | Y(1) | 64 | 64 | 730108F00-086-G |  | Fuse,Fast acting,500V,30A,G,SMD | LITTELFUSE FAR EAST PTE LTD | 0505030.MXP | 2 | G | FS27,FS28 |  |  |  |  |  |  |
| Multi | ND | ND | Y(1) | 65 | 65 | 730100L00-086-G |  | Fuse,Very fast acting,125V,5A,G,SMD | LITTELFUSE FAR EAST PTE LTD | 0451005.MRL | 7 | G | PBFFS1,PBEFS1,PAMFS1,PAFFS1,PAEFS1,PAMFS2,FS29 |  |  |  |  |  |  |
|  |  |  |  |  | 65 | 730107B01-088-G |  | Fuse,Very fast acting,125V,5A,G,SMD | COOPER BUSSMANN, INC. | CB61F5A-TR2 |  | G |  |  |  |  |  |  |  |
| Single | ND | ND | Y(1) | 66 | 66 | 730101C00-086-G |  | Fuse,Slow blow,125V,30A,G,SMD | LITTELFUSE FAR EAST PTE LTD | 0456030.ER | 1 | G | FS30 |  |  |  |  |  |  |
| Multi | ND |  | N | 67 | 67 | 87898-0318 |  | CONN,Header,Pin Header,1X3,V/T,2.54mm,30u,G,SMD-3 | MOLEX INCORPORATED | 87898-0318 | 10 | G | J_BMC_DEBUG1,J1,J4,J5,J36,J41,J43,J48,J147,J149 |  |  |  |  |  |  |
|  |  |  |  |  | 67 | 34068LN00-317-G |  | CONN,Header,Pin Header,1X3,V/T,2.54mm,30u,G,SMD-3 | MOLEX INCORPORATED | 87898-0315 |  | G |  |  |  |  |  |  |  |
|  |  |  |  |  | 67 | 34068HT00-245-G |  | CONN,Header,Pin Header,1X3,V/T,Bla,2.54mm,30u,SMD-3 | AMPHENOL SHANGHAI CORP. | G800MU305010EU |  | G |  |  |  |  |  |  |  |
|  |  |  |  |  | 67 | 34068GU00-309-G |  | CONN,Header,Pin Header,1X3,V/T,Bla,2.54mm,30u,SMD-3 | SAMTEC INC. | TSM-103-01-S-SV-P-TR |  | G |  |  |  |  |  |  |  |
| Multi | N |  | N | 68 | 68 | 87898-0458 |  | CONN,Pin Header,1X4,V/T,Bla,2.54mm,30u,G,SMD-4 | MOLEX INCORPORATED | 87898-0458 | 1 | G | J148 |  |  |  |  |  |  |
|  |  |  |  |  | 68 | 340672300-317-G |  | CONN,Pin Header,1X4,V/T,Bla,2.54mm,30u,G,SMD-4 | MOLEX INCORPORATED | 87898-0455 |  | G |  |  |  |  |  |  |  |
|  |  |  |  |  | 68 | 340692T00-245-G |  | CONN,Header,Pin Header,1X4,V/T,Bla,2.54mm,30u,G,SMD-4 | AMPHENOL SHANGHAI CORP. | G800MR304010HR |  | G |  |  |  |  |  |  |  |
|  |  |  |  |  | 68 | 34068VT00-GRT-G |  | CONN,Header,Pin Header,1X4,V/T,Bla,2.54mm,30u,G,SMD-4 | PINREX TECHNOLOGY CORP. | 212-91-04SBEJ |  | G |  |  |  |  |  |  |  |
| Multi | N |  | N | 69 | 69 | 52112H800-289-G |  | LED,Blu,LTST-C193TBKT-LO,5V,20mA,G,SMD | LITE-ON TECHNOLOGY CORPORATION | LTST-C193TBKT-LO | 1 | G | LED1 |  |  |  |  |  |  |
|  |  |  |  |  | 69 | 52112H900-354-G |  | LED LAMP,LG-192DBK-CT/T-SD,Blue,24mcd@IF=5mA,475nm,999.9999V,20mA,N/A,,SMD0603,2P,G | Ligitek Electronics Co., Ltd. | LG-192DBK-CT/T-SD |  | G |  |  |  |  |  |  |  |
| Multi | N | 1 | N | 70 | 70 | 52111AE00-289-G |  | LED,Ora,LTST-C281KFKT-5A,5V,30mA,G,SMD0402 | LITE-ON TECHNOLOGY CORPORATION | LTST-C281KFKT-5A | 2 | G | LED2,LED6 |  |  |  |  |  |  |
|  |  |  |  |  | 70 | 52113GM00-290-G |  | LED LAMP,B1851UD--05D-000214,Orange,28.5mcd@IF=20mA,605nm,5V,20mA,N/A,,SMD0402,2P,G | HARVATEK CORPORATION | B1851UD--05D-000214 |  | G |  |  |  |  |  |  |  |
| Multi | N | 1 | N | 71 | 71 | 52111J100-289-G |  | LED,Gre,LTST-C281KGKT-5A,2.3V,30mA,G,SMD0402 | LITE-ON TECHNOLOGY CORPORATION | LTST-C281KGKT-5A | 2 | G | LED3,LED7 |  |  |  |  |  |  |
|  |  |  |  |  | 71 | 52113AE00-290-G |  | LED LAMP,B1851UYG-05D-000114,Ultra Bright Yellow Green,11.25mcd@IF=5mA,571nm,5V,20mA,N/A,,SMD0402,2P,G | HARVATEK CORPORATION | B1851UYG-05D-000114 |  | G |  |  |  |  |  |  |  |
| Sole | ND |  | N | 72 | 72 | 52113AY00-289-G |  | LED,Red,LTL-42NEW8DH184P,5V,20mA,G,DIP-2 | LITE-ON TECHNOLOGY CORPORATION | LTL-42NEW8DH184P | 2 | G | LED8,LED9 |  |  |  |  |  |  |
| Single | ND |  | N | 73 | 73 | 52113B000-289-G |  | LED,Yellow,LTL-42NSV8DH184P,5V,20mA,G,DIP-2 | LITE-ON TECHNOLOGY CORPORATION | LTL-42NSV8DH184P | 2 | G | LED10,LED14 |  |  |  |  |  |  |
| Single | ND |  | N | 74 | 74 | 52113AW00-289-G |  | LED,Green,LTL-42NGY8DH184P,5V,20mA,G,DIP-2 | LITE-ON TECHNOLOGY CORPORATION | LTL-42NGY8DH184P | 2 | G | LED11,LED12 |  |  |  |  |  |  |
| Single | ND |  | N | 75 | 75 | 52113B100-289-G |  | LED,Blue,LTL42TB6NH184P,5V,30mA,G,DIP-2 | LITE-ON TECHNOLOGY CORPORATION | LTL42TB6NH184P | 1 | G | LED13 |  |  |  |  |  |  |
| Sole | N |  | N | 76 | 76 | 52110FE00-289-G |  | LED,Red,LTST-C190KRKT,2.4V,30mA,G,SMD0603 | LITE-ON TECHNOLOGY CORPORATION | LTST-C190KRKT | 3 | G | LED63,LED64,LED65 |  |  |  |  |  |  |
| Multi | N | 1 | N | 77 | 77 | 52110LN00-289-G |  | LED,Gre,LTST-C191KGKT,2.4V,30mA,G,SMD0603 | LITE-ON TECHNOLOGY CORPORATION | LTST-C191KGKT | 37 | G | LED66,LED67,LED68,LED69,LED70,LED71,LED72,LED73,LED74,LED75,LED76,LED77,LED78,LED79,LED80,LED81,LED82,LED83,LED84,LED85,LED86,LED87,LED88,LED89,LED90,LED91,LED92,LED93,LED94,LED95,LED96,LED97,LED98,LED99,LED100,LED101,LED102 |  |  |  |  |  |  |
|  |  |  |  |  | 77 | 52110K100-030-G |  | LED LAMP,SML-512MWT86,Green,40mcd@If=20mA,N/A,5V,25mA,N/A,,SMD0603,2P,G | ROHM CORPORATION | SML-512MWT86 |  | G |  |  |  |  |  |  |  |
| Multi | Y | Other | Y(2) | 78 | 78 | 720108301-015-G |  | FB,600 Ohm@100MHz,+/-25%,500mA,350mOhm,G,SMD0603 | MURATA ELEC. NORTH AMERICA | BLM18EG601SN1D | 4 | G | L13,L14,L15,L16 |  |  |  |  |  |  |
|  |  |  |  |  | 78 | 720105E00-059-G |  | FB,600 Ohm@100MHz,+/-25%,500mA,400mOhm,G,SMD0603 | TAI-TECH ADVANCED ELECTRONICS CO., LTD. | FCM1608KF-601T05 |  | G |  |  |  |  |  |  |  |
|  |  |  |  |  | 78 | 720105E00-016-G |  | FB,600 Ohm@100MHz,+/-25%,500mA,400mOhm,G,SMD0603 | TDK ELECTRONICS EUROPE GMBH | MMZ1608S601AT |  | G |  |  |  |  |  |  |  |
| Multi | Y | Other | Y(2) | 79 | 79 | 720106E00-015-G |  | FB,330 Ohm@100MHz,+/-25%,500mA,300mOhm,G,SMD0603 | MURATA ELEC. NORTH AMERICA | BLM18EG331TN1D | 1 | G | L17 |  |  |  |  |  |  |
|  |  |  |  |  | 79 | 72010YW01-129-G |  | FB,Multilayer,100mOhm,330Ohm@100MHz,+/-25%,2A,,SMD0603,G | MAG.LAYERS, SCIENTIFIC-TECHNICS (KUNSHAN) CO., LTD. | GMLB-160808-0330P-N8 |  | G |  |  |  |  |  |  |  |
| Multi | ND | ND | N | 80 | 80 | 720105P00-016-G |  | FB,80 Ohm@100MHz,+/-25%,500mA,150mOhm,G,SMD0603 | TDK ELECTRONICS EUROPE GMBH | MMZ1608S800AT | 4 | G | L22,L23,L24,L25 |  |  |  |  |  |  |
|  |  |  |  |  | 80 | 72010WQ00-129-G |  | FB,Multilayer,40mOhm,80Ohm@100MHz,+/-25%,3A,,SMD0603,G | MAG.LAYERS, SCIENTIFIC-TECHNICS (KUNSHAN) CO., LTD. | GMLB-160808-0080P-N8 |  | G |  |  |  |  |  |  |  |
| Multi | ND | ND | Y(2) | 81 | 81 | 72010CB00-015-G |  | FB,22 Ohm@100MHz,+/-25%,6A,10mOhm,G,SMD0805 | MURATA ELEC. NORTH AMERICA | BLM21PG220SN1D | 3 | G | L26,L28,L47 |  |  |  |  |  |  |
|  |  |  |  |  | 81 | 72010CB00-059-G |  | FB,22 Ohm@100MHz,+/-25%,6A,10mOhm,G,SMD0805 | TAI-TECH ADVANCED ELECTRONICS CO., LTD. | HCB2012KF-220T60 |  | G |  |  |  |  |  |  |  |
|  |  |  |  |  | 81 | 72010Y600-174-G |  | FB,22 Ohm@100MHz,+/-25%,6A,8mOhm,G,SMD0805 | MAX ECHO TECHNOLOGIES CORP | BCMS201209A220 |  | G |  |  |  |  |  |  |  |
| Multi | ND |  | N | 82 | 82 | 72010A400-023-G |  | FB,80Ohm@100MHz,+/-25%,4A,10mOhm,G,SMD1206 | TAIYO ELECTRIC IND.CO.LTD | FBMJ3216HS800-T | 2 | G | L34,L36 |  |  |  |  |  |  |
|  |  |  |  |  | 82 | 72010A400-025-G |  | FB,Multilayer,10mOhm,80Ohm@100MHz,+/-25%,4A,,SMD1206,G | KEMET ELECTRONICS CORPORATION | Z1206C800APWST |  | G |  |  |  |  |  |  |  |
| Multi | ND |  | Y(2) | 83 | 83 | 72010MK00-015-G |  | FB,80 Ohm@100MHz,+/-25%,1.5A,70mOhm,G,SMD0402 | MURATA ELEC. NORTH AMERICA | BLM15PD800SN1D | 7 | G | L35,L37,L38,L39,L40,L41,L42 |  |  |  |  |  |  |
|  |  |  |  |  | 83 | 72010MK00-174-G |  | FB,80 Ohm@100MHz,+/-25%,1.5A,Multilayer,70mOhm,SMD0402,G | MAX ECHO TECHNOLOGIES CORP | ACMS100505A800 1.5A |  | G |  |  |  |  |  |  |  |
| Multi | Y | other | Y(2) | 84 | 84 | 720101M00-015-G |  | FB,600 Ohm@100MHz,+/-25%,200mA,650mOhm,G,SMD0603 | MURATA ELEC. NORTH AMERICA | BLM18BD601SN1D | 1 | G | L45 |  |  |  |  |  |  |
|  |  |  |  |  | 84 | 720103000-023-G |  | FB,600 Ohm@100MHz,+/-25%,250mA,600mOhm,G,SMD0603 | TAIYO ELECTRIC IND.CO.LTD | BK1608HM601-T |  | G |  |  |  |  |  |  |  |
| Single | ND |  | ND | 85 | 85 | 62111U700-024-G |  | ECAP,68uF,+/-20%,100V,105C,320mOhm,G,SMD12.5*13.5 | PANASONIC INDUSTRIAL CO.,LTD. | EEEFK2A680AQ | 6 | G | PSUCE1,PBACE1,PAACE1,PSUCE2,PBACE2,PAACE2 |  |  |  |  |  |  |
| Sole | N |  | Y(1) | 86 | 86 | 62111QQ00-019-G |  | ECAP,82uF,+/-20%,100V,105C,G,SMD12.5*13.5,ESR<=280mOhm | NICHICON CORPORATION | UCZ2A820MNQ1MS | 8 | G | PBMCE1,PAMCE1,PBFCE2,PBECE2,PAFCE2,PAECE2,PBACE3,PAACE3 |  |  |  |  |  |  |
| Single | N |  | Y(3) | 87 | 87 | 62120ER01-024-G |  | ECAP,SPEA,470uF,+/-20%,2.5V,105C,G,SMD2816,ESR<=3mOhm | PANASONIC INDUSTRIAL CO.,LTD. | EEFGX0E471R | 50 | G | PBNCE1,PANCE1,PBNCE2,PANCE2,PBECE3,PALCE3,PAFCE3,PAECE3,PBMCE4,PBFCE4,PBECE4,PBACE4,PAMCE4,PALCE4,PAFCE4,PAECE4,PAACE4,PBMCE5,PBFCE5,PBECE5,PBACE5,PAMCE5,PAFCE5,PAECE5,PAACE5,PBMCE6,PBFCE6,PBECE6,PBACE6,PAMCE6,PAFCE6,PAECE6,PAACE6,PBMCE7,PBLCE7,PBFCE7,PBACE7,PAMCE7,PAACE7,PBLCE8,PBACE8,PAACE8,PBACE9,PAACE9,PBACE10,PAACE10,PBACE11,PAACE11,PBACE12,PAACE12 |  |  |  |  |  |  |
| Multi | Y |  | Y(1) | 88 | 88 | 62012RJ00-015-G |  | CAP,4.7uF,+/-10%,X6S,16V,G,SMD0603 | MURATA ELEC. NORTH AMERICA | GRM188C81C475K | 34 | G | PBMC1,PBFC1,PBEC1,PBAC1,PAMC1,PAFC1,PAEC1,PAAC1,PBMC2,PBFC2,PBEC2,PBAC2,PAMC2,PAFC2,PAEC2,PAAC2,PBMC22,PBFC22,PBEC22,PBAC22,PAMC22,PAFC22,PAEC22,PAAC22,PBMC450,PBFC450,PBEC450,PBAC450,PAMC450,PAFC450,PAEC450,PAAC450,PBAC452,PAAC452 |  |  |  |  |  |  |
|  |  |  |  |  | 88 | 62012RJ00-023-G |  | CAP,4.7uF,+/-10%,X6S,16V,G,SMD0603 | TAIYO ELECTRIC IND.CO.LTD | EMK107BC6475KA-T |  | G |  |  |  |  |  |  |  |
|  |  |  |  |  | 88 | 62012RJ02-026-G |  | CAP,4.7uF,+/-10%,X6S,16V,G,SMD0603 | SAMSUNG SEMICONDUCTOR | CL10X475KO8NRNC |  | G |  |  |  |  |  |  |  |
| Multi | ND | ND | Y(1) | 89 | 89 | 62010L800-015-G |  | CAP,1nF,+/-5%,NPO(C0G),50V,G,SMD0402 | MURATA ELEC. NORTH AMERICA | GRM1555C1H102J | 16 | G | PSPC5,PIPC5,PFPC5,PEPC5,PBMC5,PBAC5,PAMC5,PAAC5,PBAC23,PAAC23,PBMC95,PAMC95,PBFC451,PBEC451,PAFC451,PAEC451 |  |  |  |  |  |  |
|  |  |  |  |  | 89 | 62010L800-026-G |  | CAP,1nF,+/-5%,NPO(C0G),50V,G,SMD0402 | SAMSUNG SEMICONDUCTOR | CL05C102JB5NNNC |  | G |  |  |  |  |  |  |  |
| Multi | N |  | Y(1) | 90 | 90 | 62011DQ00-015-G |  | CAP,27nF,+/-10%,X7R,25V,G,SMD0402 | MURATA ELEC. NORTH AMERICA | GRM155R71E273KA88D | 8 | G | PBMC6,PBFC6,PBEC6,PBAC6,PAMC6,PAFC6,PAEC6,PAAC6 |  |  |  |  |  |  |
|  |  |  |  |  | 90 | 62011DQ00-025-G |  | CAP,27nF,+/-10%,X7R,25V,G,SMD0402 | KEMET ELECTRONICS CORPORATION | C0402C273K3RAC |  | G |  |  |  |  |  |  |  |
| Single | Y | 2 | Y(3) | 91 | 91 | 620102T00-015-G |  | CAP,150pF,+/-5%,NPO(C0G),50V,G,SMD0402 | MURATA ELEC. NORTH AMERICA | GRM1555C1H151J | 8 | G | PBMC7,PBFC7,PBEC7,PBAC7,PAMC7,PAFC7,PAEC7,PAAC7 |  |  |  |  |  |  |
| Multi | ND | ND | Y(3) | 92 | 92 | 62010VD00-015-G |  | CAP,100nF,+/-10%,X7R,100V,G,SMD0603 | MURATA ELEC. NORTH AMERICA | GRM188R72A104K | 9 | G | PBEC11,PAFC11,PAEC11,PBMC12,PBFC12,PBAC12,PAMC12,PAAC12,PHAC14 |  |  |  |  |  |  |
|  |  |  |  |  | 92 | 62010VD00-026-G |  | CAP,100nF,+/-10%,X7R,100V,G,SMD0603 | SAMSUNG SEMICONDUCTOR | CL10B104KC8NNNC |  | G |  |  |  |  |  |  |  |
| Multi | N |  | Y(1) | 93 | 93 | 62011J601-015-G |  | CAP,2.2uF,+/-10%,X7R,100V,G,SMD1210 | MURATA ELEC. NORTH AMERICA | GRM32ER72A225K | 42 | G | PSUC1,PSUC2,PBMC13,PBFC13,PBEC13,PBAC13,PAMC13,PAFC13,PAEC13,PAAC13,PBMC14,PBFC14,PBEC14,PBAC14,PAMC14,PAFC14,PAEC14,PAAC14,PBMC15,PBFC15,PBEC15,PBAC15,PAMC15,PAFC15,PAEC15,PAAC15,PBAC16,PAAC16,PBEC17,PBAC17,PAAC17,PBAC18,PAAC18,PBAC19,PAAC19,PBAC20,PAFC20,PAAC20,PBMC21,PBFC21,PAMC21,PAEC21 |  |  |  |  |  |  |
|  |  |  |  |  | 93 | 62011J600-026-G |  | CAP,2.2uF,+/-10%,X7R,100V,G,SMD1210 | SAMSUNG SEMICONDUCTOR | CL32B225KCJSNNE |  | G |  |  |  |  |  |  |  |
| Multi | Y | 2 | Y(3) | 94 | 94 | 620107L00-015-G |  | CAP,2.2nF,+/-10%,X7R,50V,G,SMD0402 | MURATA ELEC. NORTH AMERICA | GRM155R71H222K | 16 | G | PSRC2,PSPC12,PIPC12,PFPC12,PEPC12,PSIC18,PETC18,PERC18,PBFC25,PBEC25,PAFC25,PBMC26,PBAC26,PAMC26,PAAC26,PAEC516 |  |  |  |  |  |  |
|  |  |  |  |  | 94 | 620107L00-026-G |  | CAP,2.2nF,+/-10%,X7R,50V,G,SMD0402 | SAMSUNG SEMICONDUCTOR | CL05B222KB5NNNC |  | G |  |  |  |  |  |  |  |
|  |  |  |  |  | 94 | 620107L03-023-G |  | CAP,2.2nF,+/-10%,X7R,50V,G,SMD0402 | TAIYO ELECTRIC IND.CO.LTD | UMK105B7222KV-F |  | G |  |  |  |  |  |  |  |
| Single | ND | ND | Y(1) | 95 | 95 | 62011DA00-015-G |  | CAP,1uF,+/-10%,X7R,100V,G,SMD1206 | MURATA ELEC. NORTH AMERICA | GRM31CR72A105K | 6 | G | PBMC27,PBAC27,PAMC27,PAAC27,PBAC111,PAAC111 |  |  |  |  |  |  |
| Multi | ND | ND | ND | 96 | 96 | 620107500-015-G |  | CAP,3.9nF,+/-10%,X7R,50V,G,SMD0402 | MURATA ELEC. NORTH AMERICA | GRM155R71H392K | 2 | G | PBAC125,PAAC125 |  |  |  |  |  |  |
|  |  |  |  |  | 96 | 620107500-026-G |  | CAP,3.9nF,+/-10%,X7R,50V,G,SMD0402 | SAMSUNG SEMICONDUCTOR | CL05B392KB5NNNC |  | G |  |  |  |  |  |  |  |
|  |  |  |  |  | 96 | 620107500-023-G |  | CAP,3.9nF,+/-10%,X7R,50V,G,SMD0402 | TAIYO ELECTRIC IND.CO.LTD | UMK105B7392KV-F |  | G |  |  |  |  |  |  |  |
| Multi | N |  | Y(3) | 97 | 97 | 620127602-015-G |  | CAP,47uF,+/-20%,X6S,4V,G,SMD0805 | MURATA ELEC. NORTH AMERICA | GRM21BC80G476M | 684 | G | PBNC18,PANC18,PBNC19,PANC19,PUAC20,PSAC20,PRAC20,PQAC20,PPAC20,PIAC20,PFAC20,PEAC20,PBNC20,PANC20,PUAC21,PSAC21,PRAC21,PQAC21,PPAC21,PIAC21,PFAC21,PEAC21,PBNC21,PANC21,PUAC22,PSAC22,PRAC22,PQAC22,PPAC22,PIAC22,PFAC22,PEAC22,PBNC22,PANC22,PUAC23,PSAC23,PRAC23,PQAC23,PPAC23,PIAC23,PFAC23,PEAC23,PBNC23,PANC23,PUAC24,PSAC24,PRAC24,PQAC24,PPAC24,PIAC24,PFAC24,PEAC24,PUAC25,PSAC25,PRAC25,PQAC25,PPAC25,PIAC25,PFAC25,PEAC25,PALC25,PALC26,PALC27,PALC28,PALC29,PALC30,PALC31,PALC32,PALC33,PALC34,PBLC45,PBLC46,PBLC47,PBLC48,PBLC49,PBLC50,PBLC51,PBLC52,PBLC53,PBLC63,PBMC73,PAMC73,PBMC74,PAMC74,PBMC75,PAMC75,PBMC76,PAMC76,PBMC77,PAMC77,PBMC78,PAMC78,PBMC79,PAMC79,PBMC80,PAMC80,PBMC81,PAMC81,PBMC82,PAMC82,PBMC83,PAMC83,PBMC84,PAMC84,PBMC85,PAMC85,PBMC86,PAMC86,PBMC87,PAMC87,PBMC88,PAMC88,PBMC89,PAMC89,PBMC90,PAMC90,PBMC91,PAMC91,PBMC92,PAMC92,PBMC93,PAMC93,PBMC94,PAMC94,PBMC96,PAMC96,PBMC97,PAMC97,PBMC98,PAMC98,PBMC99,PAMC99,PBMC100,PAMC100,PBMC101,PAMC101,PBMC102,PAMC102,PBMC103,PAMC103,PBAC167,PAAC167,PBAC168,PAAC168,PBAC169,PAAC169,PBAC170,PAAC170,PBAC171,PAAC171,PBAC172,PAAC172,PBAC173,PAAC173,PBAC174,PAAC174,PBAC175,PAAC175,PBAC176,PAAC176,PBAC177,PAAC177,PBAC178,PAAC178,PBAC179,PAAC179,PBAC180,PAAC180,PBAC181,PAAC181,PBAC182,PAAC182,PBAC183,PAAC183,PBAC184,PAAC184,PBAC185,PAAC185,PBAC186,PAAC186,PBAC187,PAAC187,PBAC188,PAAC188,PBAC189,PAAC189,PBAC190,PAAC190,PBAC191,PAAC191,PBAC192,PAAC192,PBAC193,PAAC193,PBAC194,PAAC194,PBAC195,PAAC195,PBAC196,PAAC196,PBAC197,PAAC197,PBAC198,PAAC198,PBAC199,PAAC199,PBAC200,PAAC200,PBAC201,PAAC201,PBAC202,PAAC202,PBAC203,PAAC203,PBAC204,PAAC204,PBAC205,PAAC205,PBAC206,PAAC206,PBAC207,PAAC207,PBAC208,PAAC208,PBAC209,PAAC209,PBAC210,PAAC210,PBAC211,PAAC211,PBAC212,PAAC212,PBAC213,PAAC213,PBAC214,PAAC214,PBAC215,PAAC215,PBAC216,PAAC216,PBAC217,PAAC217,PBAC218,PAAC218,PBAC219,PAAC219,PBAC220,PAAC220,PBAC221,PAAC221,PBAC222,PAAC222,PBAC223,PAAC223,PBAC224,PAAC224,PBAC225,PAAC225,PBAC226,PAAC226,PBAC227,PAAC227,PBAC228,PAAC228,PBAC229,PAAC229,PBAC230,PAAC230,PBAC231,PAAC231,PBAC232,PAAC232,PBAC233,PAAC233,PBAC234,PAAC234,PBAC235,PAAC235,PBAC236,PAAC236,PBAC237,PAAC237,PBAC238,PAAC238,PBAC239,PAAC239,PBAC240,PAAC240,PBAC241,PAAC241,PBAC242,PAAC242,PBAC243,PAAC243,PBAC244,PAAC244,PBAC245,PAAC245,PBAC246,PAAC246,PBFC300,PBEC300,PAFC300,PAEC300,PBFC301,PBEC301,PAFC301,PAEC301,PBFC302,PBEC302,PAFC302,PAEC302,PBFC303,PBEC303,PAFC303,PAEC303,PBFC304,PBEC304,PAFC304,PAEC304,PBFC305,PBEC305,PAFC305,PAEC305,PBFC306,PBEC306,PAFC306,PAEC306,PBFC307,PBEC307,PAFC307,PAEC307,PBFC308,PBEC308,PAFC308,PAEC308,PBFC309,PBEC309,PAFC309,PAEC309,PBFC310,PBEC310,PAFC310,PAEC310,PBFC311,PBEC311,PAFC311,PAEC311,PBFC312,PBEC312,PAFC312,PAEC312,PBFC313,PBEC313,PAFC313,PAEC313,PBFC314,PBEC314,PAFC314,PAEC314,PBFC315,PBEC315,PAFC315,PAEC315,PBFC316,PBEC316,PAFC316,PAEC316,PBFC317,PBEC317,PAFC317,PAEC317,PBFC318,PBEC318,PAFC318,PAEC318,PBFC319,PBEC319,PAFC319,PAEC319,PBFC320,PBEC320,PAFC320,PAEC320,PBFC321,PBEC321,PAFC321,PAEC321,PBFC322,PBEC322,PAFC322,PAEC322,PBFC323,PBEC323,PAFC323,PAEC323,PBFC324,PBEC324,PAFC324,PAEC324,PBFC325,PBEC325,PAFC325,PAEC325,PBFC326,PBEC326,PAFC326,PAEC326,PBFC327,PBEC327,PAFC327,PAEC327,PBFC328,PBEC328,PAFC328,PAEC328,PBFC329,PBEC329,PAFC329,PAEC329,PBFC330,PBEC330,PAFC330,PAEC330,PBFC331,PBEC331,PAFC331,PAEC331,PBFC332,PBEC332,PAFC332,PAEC332,PBFC333,PBEC333,PAFC333,PAEC333,PBFC334,PBEC334,PAFC334,PAEC334,PBFC335,PBEC335,PAFC335,PAEC335,PBFC336,PBEC336,PAFC336,PAEC336,PBFC337,PBEC337,PAFC337,PAEC337,PBFC338,PBEC338,PAFC338,PAEC338,PBFC339,PBEC339,PAFC339,PAEC339,PBFC340,PBEC340,PAFC340,PAEC340,PBFC341,PBEC341,PAFC341,PAEC341,PBFC342,PBEC342,PAFC342,PAEC342,PBFC343,PBEC343,PAFC343,PAEC343,PBFC344,PBEC344,PAFC344,PAEC344,PBFC345,PBEC345,PAFC345,PAEC345,PBFC346,PBEC346,PAFC346,PAEC346,PBFC347,PBEC347,PAFC347,PAEC347,PBFC348,PBEC348,PAFC348,PAEC348,PBFC349,PBEC349,PAFC349,PAEC349,PBFC350,PBEC350,PAFC350,PAEC350,PBFC351,PBEC351,PAFC351,PAEC351,PBFC352,PBEC352,PAFC352,PAEC352,PBFC353,PBEC353,PAFC353,PAEC353,PBFC354,PBEC354,PAFC354,PAEC354,PBFC355,PBEC355,PAFC355,PAEC355,PBFC356,PBEC356,PAFC356,PAEC356,PBFC357,PBEC357,PAFC357,PAEC357,PBFC358,PBEC358,PAFC358,PAEC358,PBFC359,PBEC359,PAFC359,PAEC359,PBFC360,PBEC360,PAFC360,PAEC360,PBFC361,PBEC361,PAFC361,PAEC361,PBFC362,PBEC362,PAFC362,PAEC362,PBFC363,PBEC363,PAFC363,PAEC363,PBFC364,PBEC364,PAFC364,PAEC364,PBFC365,PBEC365,PAFC365,PAEC365,PBFC366,PBEC366,PAFC366,PAEC366,PBFC367,PBEC367,PAFC367,PAEC367,PBFC368,PBEC368,PAFC368,PAEC368,PBFC369,PBEC369,PAFC369,PAEC369,PBFC370,PBEC370,PAFC370,PAEC370,PBFC371,PBEC371,PAFC371,PAEC371,PBFC372,PBEC372,PAFC372,PAEC372,PBFC373,PBEC373,PAFC373,PAEC373,PBFC374,PBEC374,PAFC374,PAEC374,PBFC375,PBEC375,PAFC375,PAEC375,PBFC376,PBEC376,PAFC376,PAEC376,PBFC377,PBEC377,PAFC377,PAEC377,PBFC378,PBEC378,PAFC378,PAEC378,PBFC379,PBEC379,PAFC379,PAEC379,PBFC380,PBEC380,PAFC380,PAEC380,PBFC381,PBEC381,PAFC381,PAEC381,PBFC382,PBEC382,PAFC382,PAEC382,PBFC383,PBEC383,PAFC383,PAEC383,PBFC384,PBEC384,PAFC384,PAEC384,PBFC385,PBEC385,PAFC385,PAEC385,PBFC386,PBEC386,PAFC386,PAEC386,PBFC387,PBEC387,PAFC387,PAEC387,PBFC388,PBEC388,PAFC388,PAEC388,PBFC389,PBEC389,PAFC389,PAEC389,PBFC390,PBEC390,PAFC390,PAEC390,PBFC391,PBEC391,PAFC391,PAEC391,PBFC392,PBEC392,PAFC392,PAEC392,PBFC393,PBEC393,PAFC393,PAEC393,PBFC394,PBEC394,PAFC394,PAEC394,PBFC395,PBEC395,PAFC395,PAEC395 |  |  |  |  |  |  |
|  |  |  |  |  | 97 | 620127600-023-G |  | CAP,47uF,+/-20%,X6S,4V,G,SMD0805 | TAIYO ELECTRIC IND.CO.LTD | AMK212BC6476MG-T |  | G |  |  |  |  |  |  |  |
|  |  |  |  |  | 97 | 620127600-026-G |  | CAP,47uF,+/-20%,X6S,4V,G,SMD0805 | SAMSUNG SEMICONDUCTOR | CL21X476MRYNNNE |  | G |  |  |  |  |  |  |  |
| Multi |  |  | Y(3) | 98 | 98 | 62010GS00-015-G |  | CAP,15nF,+/-10%,X7R,25V,G,SMD0603 | MURATA ELEC. NORTH AMERICA | GRM188R71E153K | 8 | G | PBMC400,PBFC400,PBEC400,PBAC400,PAMC400,PAFC400,PAEC400,PAAC400 |  |  |  |  |  |  |
|  |  |  |  |  | 98 | 620106B00-026-G |  | CAP,15nF,+/-10%,X7R,25V,G,SMD0603 | SAMSUNG SEMICONDUCTOR | CL10B153KA8NNNC |  | G |  |  |  |  |  |  |  |
|  |  |  |  |  | 98 | 620106B00-025-G |  | CAP,15nF,+/-10%,X7R,25V,G,SMD0603 | KEMET ELECTRONICS CORPORATION | C0603C153K3RAC |  | G |  |  |  |  |  |  |  |
| Multi | N |  | N | 99 | 99 | 520103B00-185-G |  | Diode,Rectifier&Switching,MMBD1205,100V,200mA,G,SOT-23-3,SMD | FAIRCHILD SEMICONDUCTOR CORP | MMBD1205 | 8 | G | PBMD1,PBFD1,PBED1,PBAD1,PAMD1,PAFD1,PAED1,PAAD1 |  |  |  |  |  |  |
|  |  |  |  |  | 99 | 52010A100-237-G |  | Diode,Rectifier&Switching,100V,200mA,G,SOT-23-3,SMD | DIODES INCORPORATION | MMBD3004A-7-F |  | G |  |  |  |  |  |  |  |
| Sole | ND |  | N | 100 | 100 | 52030TQ00-237-G |  | Diode,Schottky,BAS40-06-7-F,40V,200mA,G,SOT-23-3,SMD | DIODES INCORPORATION | BAS40-06-7-F | 8 | G | PBMD3,PBFD3,PBED3,PBAD3,PAMD3,PAFD3,PAED3,PAAD3 |  |  |  |  |  |  |
| Multi | ND | ND | Y(1) | 101 | 101 | 730100M00-086-G |  | Fuse,Very fast acting,125V,10A,G,SMD | LITTELFUSE FAR EAST PTE LTD | 0451010.MRL | 4 | G | PSUFS1,PBAFS1,PAAFS1,PSUFS2 |  |  |  |  |  |  |
|  |  |  |  |  | 101 | 730109A00-088-G |  | Fuse,Fast acting,125V,10A,G,SMD | COOPER BUSSMANN, INC. | CB61F10A-TR2 |  | G |  |  |  |  |  |  |  |
| Multi | N |  | N | 102 | 102 | 63035NQ00-029-G |  | IND,0.1uH@100KHz,+/-20%,11.5A,6mOhm,SHLD,G,SMD | VISHAY ENTER TECHNO LOGY.INC | IHLP1616ABERR10M01 | 18 | G | PBML1,PBAL1,PAML1,PAAL1,PBFL2,PBEL2,PAFL2,PAEL2,PBML3,PBFL3,PBEL3,PBAL3,PAML3,PAFL3,PAEL3,PAAL3,PBAL5,PAAL5 |  |  |  |  |  |  |
|  |  |  |  |  | 102 | 63032QU00-034-G |  | Coil Ind,Shielded(SHLD),100nH@100KHz,+/-20%,12A,4mOhm,SMD,4.15*4.0*1.8,G | CYNTEC CO. LTD | PCMB042T-R10MS |  | G |  |  |  |  |  |  |  |
| Sole | ND |  | N | 103 | 103 | 63035R700-57M-G |  | IND,375nH@1MHz,+/-5%,16A,1.15mOhm,SHLD,G,SMD | Eaton Corporation | CTX01-19603-R | 2 | G | PBAL2,PAAL2 |  |  |  |  |  |  |
| Multi | ND | ND | N | 104 | 104 | 510201900-185-G |  | TRANS P,MMBT3906,40V,0.2A,G,SOT23-3,SMD | FAIRCHILD SEMICONDUCTOR CORP | MMBT3906 | 16 | G | PBMQ1,PBFQ1,PBEQ1,PBAQ1,PAMQ1,PAFQ1,PAEQ1,PAAQ1,PBMQ2,PBFQ2,PBEQ2,PBAQ2,PAMQ2,PAFQ2,PAEQ2,PAAQ2 |  |  |  |  |  |  |
|  |  |  |  |  | 104 | 510201900-031-G |  | TRANS P,MMBT3906,40V,0.2A,G,SOT23-3,SMD | NXP SEMICONDUCTORS | MMBT3906 |  | G |  |  |  |  |  |  |  |
|  |  |  |  |  | 104 | 510200600-237-G |  | TRANS P,MMBT3906-7-F,40V,0.2A,G,SOT23-3,SMD | DIODES INCORPORATION | MMBT3906-7-F |  | G |  |  |  |  |  |  |  |
| Multi | N |  | N | 105 | 105 | 51032DL00-237-G |  | MOS N,DMT10H014LSS-13,100V,8.9A,15m@10V,G,SO-8,SMD | DIODES INCORPORATION | DMT10H014LSS-13 | 8 | G | PBMQ10,PBAQ10,PAMQ10,PAAQ10,PBFQ11,PBEQ11,PAFQ11,PAEQ11 |  |  |  |  |  |  |
|  |  |  |  |  | 105 | 51032FL00-029-G |  | MOS N,Si4190ADY-T1-GE3,100V,18.4A,8.8m@10V,G,SO-8,SMD | VISHAY ENTER TECHNO LOGY.INC | Si4190ADY-T1-GE3 |  | G |  |  |  |  |  |  |  |
| Multi | ND | ND | Y(3) | 106 | 106 | 510100W00-237-G |  | TRANS N,MMBT3904-7-F,40V,0.2A,G,SOT23-3,SMD | DIODES INEORPORATION | MMBT3904-7-F | 18 | G | Q8,PHAQ8,PBMQ11,PBAQ11,PAMQ11,PAAQ11,PBFQ12,PBEQ12,PAFQ12,PAEQ12,Q85,Q86,Q87,Q88,Q89,Q90,Q91,Q92 |  |  |  |  |  |  |
|  |  |  |  |  | 106 | 510100500-031-G |  | TRANS N,PMBT3904,40V,0.2A,G,SOT23-3,SMD | NXP SEMICONDUCTORS | PMBT3904 |  | G |  |  |  |  |  |  |  |
|  |  |  |  |  | 106 | 510101700-185-G |  | TRANS N,MMBT3904,40V,0.2A,G,SOT23-3,SMD | FAIRCHILD SEMICONDUCTOR CORP | MMBT3904 |  | G |  |  |  |  |  |  |  |
| Multi | ND | ND | N | 107 | 107 | 510302R00-185-G |  | MOS N,BSS138,50V,0.22A,6ohm@4.5V,G,SOT23-3,SMD | FAIRCHILD SEMICONDUCTOR CORP | BSS138 | 8 | G | PBFQ10,PBEQ10,PAFQ10,PAEQ10,PBMQ12,PBAQ12,PAMQ12,PAAQ12 |  |  |  |  |  |  |
|  |  |  |  |  | 107 | 510309C00-237-G |  | MOS N,BSS138-7-F,50V,0.2A,3.5ohm@10V,G,SOT23-3,SMD | DIODES INCORPORATION | BSS138-7-F |  | G |  |  |  |  |  |  |  |
|  |  |  |  |  | 107 | 510301D00-223-G |  | MOS N,BSS138LT1G,50V,0.2A,3.5ohm@5V,G,SOT23-3,SMD | ON SEMICONDUCTOR CORP | BSS138LT1G |  | G |  |  |  |  |  |  |  |
| Multi | N | ND | Y(4) | 108 | 108 | 610108300-017-G |  | RES,0 Ohm,+/-5%,1/10W,G,SMD0603 | KOA SPEER ELECTRONICS, INC. | RK73Z1JTTD | 108 | G | PUAR1,PSIR1,PSAR1,PRAR1,PQAR1,PPAR1,PIAR1,PFAR1,PETR1,PERR1,PEAR1,PBMR1,PBFR1,PBER1,PBAR1,PAMR1,PAFR1,PAER1,PAAR1,PUAR3,PSIR3,PSAR3,PRAR3,PQAR3,PPAR3,PIAR3,PFAR3,PETR3,PERR3,PEAR3,PUAR9,PSIR9,PSAR9,PRAR9,PQAR9,PPAR9,PIAR9,PFAR9,PETR9,PERR9,PEAR9,PBNR10,PANR10,PBNR13,PANR13,PBAR66,PBMR68,PAMR70,PBER71,PAFR71,PAER71,PAAR71,PBFR72,PBMR78,PAMR78,R133,R142,R153,R163,R174,R184,R196,R205,R217,R226,R238,R247,R258,R268,R280,R289,PBER308,PBFR400,PBAR400,PAFR400,PAER400,PAAR400,R488,R497,R508,R518,R529,R539,R551,R560,R572,R581,R593,R602,R614,R623,R635,R644,R1028,R1742,R1743,R1744,R1747,R1748,R1749,R1755,R1761,R1762,R1763,R1764,R1765,R1766,R1767 |  |  |  |  |  |  |
|  |  |  |  |  | 108 | 610108300-024-G |  | RES,0 Ohm,+/-5%,1/10W,G,SMD0603 | PANASONIC INDUSTRIAL CO.,LTD. | ERJ3GEY0R00V |  | G |  |  |  |  |  |  |  |
| Multi | N | ND | Y(4) | 109 | 109 | 610107A00-017-G |  | RES,0 Ohm,+/-5%,1/16W,G,SMD0402 | KOA SPEER ELECTRONICS, INC. | RK73Z1ETTP | 718 | G | R1,R2,PSTR2,PSPR2,PSLR2,PSFR2,PSER2,PSDR2,PQPR2,PIPR2,PFPR2,PEPR2,PEER2,PEDR2,PBFR2,PBER2,PBAR2,PAFR2,PAER2,PAAR2,PBNR3,PBER3,PBAR3,PANR3,PAER3,PAAR3,PBNR4,PBFR4,PBAR4,PANR4,PAFR4,PAAR4,PBAR5,PAAR5,R6,PAMR6,PAAR6,R7,PSPR7,PIPR7,PFPR7,PEPR7,PBFR7,PAER7,PSRR8,PSPR8,PSLR8,PSFR8,PSDR8,PQPR8,PIPR8,PFRR8,PFPR8,PEPR8,PEER8,PEDR8,PAFR8,PAER8,PSTR9,PSLR9,PSFR9,PSER9,PSDR9,PQPR9,PFRR9,PEER9,PEDR9,PBER9,PBAR9,PAMR9,PHAR10,PBFR10,PAAR10,PBMR11,PBER11,PAFR11,PUAR12,PSIR12,PSAR12,PRAR12,PQAR12,PPAR12,PIAR12,PHAR12,PFAR12,PETR12,PERR12,PEAR12,PBNR12,PANR12,PBER13,PAAR13,PUAR14,PSRR14,PSPR14,PSAR14,PRAR14,PQAR14,PPAR14,PIPR14,PIAR14,PFPR14,PFAR14,PEPR14,PEAR14,PBMR14,PBFR14,PBAR14,PAFR14,PUAR15,PSTR15,PSRR15,PSLR15,PSFR15,PSER15,PSDR15,PSAR15,PRAR15,PQPR15,PQAR15,PPAR15,PIAR15,PFRR15,PFAR15,PEER15,PEDR15,PEAR15,PBFR15,PBER15,PBAR15,PAFR15,PAER15,PAAR15,PSIR16,PETR16,PERR16,PBMR16,PBAR16,PAMR16,PAER16,PALR17,PSTR18,PSLR18,PSFR18,PSER18,PSDR18,PQPR18,PFRR18,PEER18,PEDR18,PBMR18,PBFR18,PBER18,PBAR18,PAMR18,PAFR18,PAER18,PAAR18,PBLR19,PBNR20,PANR20,PSRR22,PSPR22,PIPR22,PFPR22,PEPR22,PBMR22,PBFR22,PBER22,PBAR22,PAMR22,PAFR22,PAER22,PAAR22,PHAR24,PHAR25,PBMR25,PBFR25,PBER25,PBAR25,PAMR25,PAFR25,PAER25,PAAR25,PBMR28,PBFR28,PBER28,PBAR28,PAMR28,PAFR28,PAER28,PAAR28,R29,R30,PBMR30,PBFR30,PBER30,PBAR30,PAMR30,PAFR30,PAER30,PAAR30,PHAR31,PHAR32,PBMR32,PBFR32,PBER32,PBAR32,PAMR32,PAFR32,PAER32,PAAR32,PHAR33,PBMR33,PBFR33,PBER33,PBAR33,PAMR33,PAFR33,PAER33,PAAR33,PHAR34,PBMR35,PBFR35,PBER35,PBAR35,PAMR35,PAFR35,PAER35,PAAR35,PBMR36,PBFR36,PBER36,PBAR36,PAMR36,PAFR36,PAER36,PAAR36,PBMR38,PBFR38,PBER38,PBAR38,PAMR38,PAFR38,PAER38,PAAR38,PBMR39,PBAR39,PAMR39,PAAR39,PBMR42,PBFR42,PBER42,PBAR42,PAMR42,PAFR42,PAER42,PAAR42,PBMR46,PAMR46,PBMR56,PBFR56,PBER56,PBAR56,PAMR56,PAFR56,PAER56,PAAR56,PBMR66,PAMR67,PAMR68,PAAR68,PBAR69,PAAR69,R70,PBMR70,PBAR70,R71,R72,PBAR72,PAAR72,R73,R74,R75,PAFR77,PAER77,PBFR78,PBER78,PAFR78,PAER78,R79,PBMR79,PBFR79,PBER79,PAMR79,PAFR79,PAER79,R80,PBFR80,R81,PBER81,PBAR81,PAFR81,PAER81,PAAR81,R82,PBFR82,PBER82,PAER82,R83,R84,R85,R86,R87,PBMR87,PBER87,PAMR87,PBER89,PBAR89,PAFR89,PAER89,PAAR89,PBFR90,PBER93,PAFR93,PAER93,PBFR94,PBER96,PAFR96,PAER96,PBFR97,PBAR101,PAAR101,PBMR103,PAMR103,PBMR104,PAMR104,PBER105,PAFR105,PAER105,PBFR106,PBER106,PAFR106,PAER106,PBFR107,PBMR110,PBAR110,PAMR110,PAAR110,PBMR111,PAMR111,PBER112,PAFR112,PAER112,PBFR113,PBER113,PAFR113,PAER113,PBFR114,PBMR115,PAMR115,PBMR116,PBAR116,PAMR116,PAAR116,PBER117,PBAR117,PAFR117,PAER117,PAAR117,PBFR118,PBER118,PAFR118,PAER118,PBFR119,PBAR121,PAAR121,PBAR122,PAAR122,PBFR302,PBER302,PBAR302,PAFR302,PAER302,PAAR302,R303,PBMR303,PBFR303,PBER303,PBAR303,PAMR303,PAFR303,PAER303,PAAR303,R306,R308,PBMR308,PBAR308,PAMR308,PAAR308,R309,PBMR309,PBAR309,PAMR309,PAAR309,PBFR310,PAFR310,PAER310,R311,PBER311,R312,PBFR312,PAFR312,PAER312,R313,PBER313,R314,R315,R316,R317,R320,R321,R322,R323,R324,R325,R326,R331,R363,R364,R368,R369,R414,R415,R428,R429,R430,R431,R433,R434,R437,R438,R439,R440,R467,R473,R474,R477,R478,R479,PSUR500,PBNR500,PBMR500,PBFR500,PBER500,PANR500,PAMR500,PAFR500,PAER500,PAAR500,PSUR501,PBNR501,PBMR501,PBFR501,PBER501,PANR501,PAMR501,PAFR501,PAER501,PAAR501,PBAR502,PBAR503,PBFR514,PBER514,PAFR514,PBFR515,PBER515,PAFR515,PAER515,PBFR516,PBER516,PAFR516,PAER516,PAER517,PBMR607,PBAR607,PAMR607,PAAR607,PBMR608,PBAR608,PAMR608,PAAR608,R744,R745,R747,R750,R754,R757,R760,R761,R785,R798,R802,R810,R812,R813,R824,R826,R895,R896,R899,R900,R909,R911,R918,R919,R921,R923,R924,R926,R928,R930,R931,R941,R946,R947,R951,R952,R973,R974,R979,R987,R1004,R1005,R1073,R1082,R1086,R1099,R1100,R1116,R1117,R1120,R1121,R1122,R1123,R1124,R1130,R1131,R1132,R1133,R1134,R1143,R1145,R1146,R1158,R1160,R1166,R1167,R1168,R1170,R1177,R1178,R1179,R1180,R1182,R1187,R1188,R1191,R1192,R1194,R1200,R1201,R1203,R1204,R1207,R1208,R1214,R1215,R1216,R1228,R1233,R1235,R1236,R1238,R1241,R1242,R1243,R1244,R1245,R1246,R1247,R1248,R1249,R1259,R1260,R1264,R1268,R1272,R1276,R1281,R1282,R1283,R1284,R1285,R1286,R1289,R1290,R1291,R1292,R1293,R1297,R1321,R1322,R1330,R1339,R1344,R1360,R1362,R1369,R1370,R1372,R1373,R1375,R1376,R1406,R1407,R1432,R1433,R1434,R1435,R1436,R1437,R1438,R1439,R1442,R1443,R1472,R1473,R1478,R1491,R1496,R1497,R1501,R1503,R1510,R1514,R1519,R1522,R1527,R1528,R1531,R1532,R1549,R1552,R1554,R1555,R1599,R1600,R1720,R1721,R1722,R1724,R1725,R1752,R1753,R1776,R1803,R1804,R1805,R1806,R1807,R1808,R1809,R1810,R1812,R1813,R1814,R1815,R1816,R1817,R1818,R1819,R1825,R1826,R1832,R1833,R1835,R1837,R1840,R1841,R1842,R1843,R1848,R1849,R1850,R2045,R2046,R2047,R2048,R2049,R2050,R2051,R2052,PSPR3001,PIPR3001,PFPR3001,PEPR3001,PSPR3002,PIPR3002,PFPR3002,PEPR3002,PSRR3003,PSPR3003,PIPR3003,PFPR3003,PEPR3003,PSRR3005,PSRR3008 |  |  |  |  |  |  |
|  |  |  |  |  | 109 | 610107A00-024-G |  | RES,0 Ohm,+/-5%,1/16W,G,SMD0402 | PANASONIC INDUSTRIAL CO.,LTD. | ERJ2GE0R00X |  | G |  |  |  |  |  |  |  |
|  |  |  |  |  | 109 | 610107A00-029-G |  | RES,0 Ohm,+/-5%,1/16W,G,SMD0402 | VISHAY ENTER TECHNO LOGY.INC | CRCW04020000Z0ED |  | G |  |  |  |  |  |  |  |
| Multi | ND | ND | Y(4) | 110 | 110 | 61010PS00-017-G |  | RES,200KOhm,+/-1%,1/16W,G,SMD0402 | KOA SPEER ELECTRONICS, INC. | RK73H1ETTP2003F | 52 | G | PBER7,PAMR7,PBAR8,PAMR8,PAFR9,PAAR9,PAFR10,PAER10,PBAR11,PAER11,PBFR12,PBAR12,PAAR12,PBMR13,PBFR13,PBER14,PAAR14,PBMR15,PBMR17,PBFR17,PBER17,PBAR17,PAMR17,PAFR17,PAER17,PAAR17,PBMR21,PBFR21,PBER21,PBAR21,PAMR21,PAFR21,PAER21,PAAR21,PBMR24,PBFR24,PBER24,PBAR24,PAMR24,PAFR24,PAER24,PAAR24,PBMR27,PBFR27,PBER27,PBAR27,PAMR27,PAFR27,PAER27,PAAR27,PBAR127,PAAR127 |  |  |  |  |  |  |
|  |  |  |  |  | 110 | 61010PS00-029-G |  | RES,200KOhm,+/-1%,1/16W,G,SMD0402 | VISHAY ENTER TECHNO LOGY.INC | CRCW0402200KFKED |  | G |  |  |  |  |  |  |  |
| Multi | N |  | Y(5) | 111 | 111 | 61100YD00-017-G |  | RES,9.53KOhm,+/-0.1%,1/16W,G,SMD0402 | KOA SPEER ELECTRONICS, INC. | RN731ETTP9531B25 | 2 | G | PBAR26,PAAR26 |  |  |  |  |  |  |
|  |  |  |  |  | 111 | 61100YD00-024-G |  | RES,9.53KOhm,+/-0.1%,1/16W,G,SMD0402 | PANASONIC INDUSTRIAL CO.,LTD. | ERA2AEB9531X |  | G |  |  |  |  |  |  |  |
| Multi | N | ND | Y(4) | 112 | 112 | 61010L300-017-G |  | RES,1KOhm,+/-1%,1/16W,G,SMD0402 | KOA SPEER ELECTRONICS, INC. | RK73H1ETTP1001F | 33 | G | PHAR9,PALR16,PBLR18,PBNR21,PANR21,PBMR40,PBFR40,PBER40,PBAR40,PAMR40,PAFR40,PAER40,PAAR40,R865,R866,R1155,R1169,R1181,R1193,R1205,R1217,R1258,R1329,R1333,R1334,R1335,R1498,R1500,R1729,R1733,R1737,R1741,R1824 |  |  |  |  |  |  |
|  |  |  |  |  | 112 | 61010L300-029-G |  | RES,1KOhm,+/-1%,1/16W,G,SMD0402 | VISHAY ENTER TECHNO LOGY.INC | CRCW04021K00FKED |  | G |  |  |  |  |  |  |  |
|  |  |  |  |  | 112 | 61010L300-024-G |  | RES,1KOhm,+/-1%,1/16W,G,SMD0402 | PANASONIC INDUSTRIAL CO.,LTD. | ERJ2RKF1001X |  | G |  |  |  |  |  |  |  |
| Multi | N | Other | Y(5) | 113 | 113 | 611008W00-017-G |  | RES,73.2KOhm,+/-0.1%,1/16W,G,SMD0402 | KOA SPEER ELECTRONICS, INC. | RN731ETTP7322B25 | 8 | G | PBMR41,PBFR41,PBER41,PBAR41,PAMR41,PAFR41,PAER41,PAAR41 |  |  |  |  |  |  |
|  |  |  |  |  | 113 | 611008W00-011-G |  | RES,73.2KOhm,+/-0.1%,1/16W,G,SMD0402 | YAGEO CORPORATION COMPONENT | RT0402BRD0773K2L |  | G |  |  |  |  |  |  |  |
|  |  |  |  |  | 113 | 611008W00-024-G |  | RES,73.2KOhm,+/-0.1%,1/16W,G,SMD0402 | PANASONIC INDUSTRIAL CO.,LTD. | ERA2AEB7322X |  | G |  |  |  |  |  |  |  |
| Multi | N | other | Y(4) | 114 | 114 | 610103Y00-017-G |  | RES,10 Ohm,+/-1%,1/10W,G,SMD0603 | KOA SPEER ELECTRONICS, INC. | RK73H1JTTD10R0F | 16 | G | PHAR8,PHAR14,PHAR15,PBMR45,PBAR45,PAMR45,PAER45,PAAR45,PBMR99,PAMR99,PBER101,PAFR101,PAER101,PBFR102,PBAR105,PAAR105 |  |  |  |  |  |  |
|  |  |  |  |  | 114 | 610103Y00-024-G |  | RES,10 Ohm,+/-1%,1/10W,G,SMD0603 | PANASONIC INDUSTRIAL CO.,LTD. | ERJ3EKF10R0V |  | G |  |  |  |  |  |  |  |
| Multi |  |  | Y(4) | 115 | 115 | 61010LD00-017-G |  | RES,6.8KOhm,+/-1%,1/16W,G,SMD0402 | KOA SPEER ELECTRONICS, INC. | RK73H1ETTP6801F | 2 | G | PBAR47,PAAR47 |  |  |  |  |  |  |
|  |  |  |  |  | 115 | 61010LD00-024-G |  | RES,6.8KOhm,+/-1%,1/16W,G,SMD0402 | PANASONIC INDUSTRIAL CO.,LTD. | ERJ2RKF6801X |  | G |  |  |  |  |  |  |  |
| Multi | ND |  | Y(4) | 116 | 116 | 61011MC02-017-G |  | Res,374 Ohm,+/-1%,1/16W,G,SMD0402 | KOA SPEER ELECTRONICS, INC. | RK73H1ETTP3740F | 8 | G | PBMR54,PBFR54,PBER54,PBAR54,PAMR54,PAFR54,PAER54,PAAR54 |  |  |  |  |  |  |
|  |  |  |  |  | 116 | 61011MC00-024-G |  | RES,thick film,374Ohm,+/-1%,1/16W,SMD0402,G | PANASONIC INDUSTRIAL CO.,LTD. | ERJ2RKF3740X |  | G |  |  |  |  |  |  |  |
|  |  |  |  |  | 116 | 61011MC00-029-G |  | RES,thick film,374Ohm,+/-1%,1/16W,SMD0402,G | VISHAY ENTER TECHNO LOGY.INC | CRCW0402374RFKED |  | G |  |  |  |  |  |  |  |
| Multi | N | ND | Y(5) | 117 | 117 | 611003D00-017-G |  | RES,1KOhm,+/-0.1%,1/16W,G,SMD0402 | KOA SPEER ELECTRONICS, INC. | RN731ETTP1001B25 | 8 | G | PBMR55,PBFR55,PBER55,PBAR55,PAMR55,PAFR55,PAER55,PAAR55 |  |  |  |  |  |  |
|  |  |  |  |  | 117 | 611003D07-029-G |  | RES,1KOhm,+/-0.1%,1/16W,G,SMD0402 | VISHAY ENTER TECHNO LOGY.INC | MCS04020D1001BE000 |  | G |  |  |  |  |  |  |  |
|  |  |  |  |  | 117 | 611003D00-024-G |  | RES,thin film,1KOhm,+/-0.1%,1/16W,SMD0402,G | PANASONIC INDUSTRIAL CO.,LTD. | ERA2AEB102X |  | G |  |  |  |  |  |  |  |
| Multi | N |  | Y(5) | 118 | 118 | 61100QV00-017-G |  | RES,49.9 Ohm,+/-0.5%,1/16W,G,SMD0402 | KOA SPEER ELECTRONICS, INC. | RN731ETTP49R9D50 | 8 | G | PBAR57,PAAR57,R932,R980,R981,R982,R983,R984 |  |  |  |  |  |  |
|  |  |  |  |  | 118 | 61100QV00-011-G |  | RES,49.9 Ohm,+/-0.5%,1/16W,G,SMD0402 | YAGEO CORPORATION COMPONENT | RT0402DRE0749R9L |  | G |  |  |  |  |  |  |  |
|  |  |  |  |  | 118 | 61100QV00-044-G |  | RES,49.9 Ohm,+/-0.5%,1/16W,G,SMD0402 | TA-I TECHNOLOGY CO., LTD. | RB04DTS49R9 |  | G |  |  |  |  |  |  |  |
| Multi | N |  | Y(5) | 119 | 119 | 61100QG00-017-G |  | RES,649 Ohm,+/-0.1%,1/16W,G,SMD0402 | KOA SPEER ELECTRONICS, INC. | RN731ETTP6490B25 | 2 | G | PBAR61,PAAR61 |  |  |  |  |  |  |
|  |  |  |  |  | 119 | 61100QG00-024-G |  | RES,649 Ohm,+/-0.1%,1/16W,G,SMD0402 | PANASONIC INDUSTRIAL CO.,LTD. | ERA2AEB6490X |  | G |  |  |  |  |  |  |  |
|  |  |  |  |  | 119 | 61100QG00-029-G |  | RES,649 Ohm,+/-0.1%,1/16W,G,SMD0402 | VISHAY ENTER TECHNO LOGY.INC | TNPW0402649RBEED |  | G |  |  |  |  |  |  |  |
| Multi | N | ND | Y(4) | 120 | 120 | 610113800-017-G |  | RES,10 Ohm,+/-1%,1/16W,G,SMD0402 | KOA SPEER ELECTRONICS, INC. | RK73H1ETTP10R0F | 27 | G | PBFR45,PBER45,PAFR45,PBER61,PAFR61,PAER61,PBFR62,PBER62,PAFR62,PAER62,PBMR63,PBFR63,PBAR63,PAMR63,PAAR63,PBMR64,PBAR64,PAMR64,PAAR64,PBFR518,PBER518,PAFR518,PBFR519,PBER519,PAFR519,PAER519,PAER520 |  |  |  |  |  |  |
|  |  |  |  |  | 120 | 610113800-029-G |  | RES,thick film,10Ohm,+/-1%,1/16W,SMD0402,G | VISHAY ENTER TECHNO LOGY.INC | CRCW040210R0FKED |  | G |  |  |  |  |  |  |  |
| Multi | ND |  | ND | 121 | 121 | 610606G00-017-G |  | RES,20mOhm,+/-1%,5W,G,SMD2512 | KOA SPEER ELECTRONICS, INC. | TLRH3APTTE20L0F | 2 | G | PBAR65,PAAR65 |  |  |  |  |  |  |
|  |  |  |  |  | 121 | 610605400-125-G |  | RES,20mOhm,+/-1%,1W,G,SMD2512 | INTERNATIONAL RESISTIVE COMPANY, INC. | LRMAP2512-R02FT4 |  | G |  |  |  |  |  |  |  |
| Multi | N | ND | ND | 122 | 122 | 61010R900-017-G |  | RES,27.4KOhm,+/-1%,1/10W,G,SMD0603 | KOA SPEER ELECTRONICS, INC. | RK73H1JTTD2742F | 8 | G | PAMR66,PAAR66,PBAR67,PBMR69,PBMR76,PAMR76,PBAR79,PAAR79 |  |  |  |  |  |  |
|  |  |  |  |  | 122 | 61010R900-011-G |  | RES,27.4KOhm,+/-1%,1/10W,G,SMD0603 | YAGEO CORPORATION COMPONENT | RC0603FR-0727K4L |  | G |  |  |  |  |  |  |  |
|  |  |  |  |  | 122 | 61010R901-029-G |  | RES,thick film,27.4KOhm,+/-1%,1/10W,SMD0603,G | VISHAY ENTER TECHNO LOGY.INC | CRCW060327K4FKEB |  | G |  |  |  |  |  |  |  |
| Multi | N | ND | Y(4) | 123 | 123 | 61010G500-017-G |  | RES,10KOhm,+/-1%,1/16W,G,SMD0402 | KOA SPEER ELECTRONICS, INC. | RK73H1ETTP1002F | 102 | G | PSUR2,PANR5,PSTR6,PSLR6,PSFR6,PSER6,PSDR6,PQPR6,PFRR6,PEER6,PEDR6,PBNR6,PUAR7,PSIR7,PSAR7,PRAR7,PQAR7,PPAR7,PIAR7,PFAR7,PETR7,PERR7,PEAR7,PHAR22,PHAR39,PAAR67,PBAR68,PBER74,PAFR74,PAER74,PBMR75,PBFR75,PAMR75,PBAR78,PAAR78,PBMR300,PBFR300,PBER300,PBAR300,PAMR300,PAFR300,PAER300,PAAR300,PBMR305,PBFR305,PBER305,PBAR305,PAMR305,PAFR305,PAER305,PAAR305,PBMR306,PBFR306,PBER306,PBAR306,PAMR306,PAFR306,PAER306,PAAR306,PBMR307,PBFR307,PBER307,PBAR307,PAMR307,PAFR307,PAER307,PAAR307,R330,R351,R353,R357,R359,R480,R481,R482,R483,R864,R910,R912,R913,R914,R915,R916,R917,R1075,R1076,R1077,R1078,R1118,R1136,R1137,R1441,R1482,R1490,R1534,R1535,R1536,R1537,R1538,R1539,R1540,PSRR3001 |  |  |  |  |  |  |
|  |  |  |  |  | 123 | 61010G500-029-G |  | RES,10KOhm,+/-1%,1/16W,G,SMD0402 | VISHAY ENTER TECHNO LOGY.INC | CRCW040210K0FKED |  | G |  |  |  |  |  |  |  |
|  |  |  |  |  | 123 | 61010G500-024-G |  | RES,10KOhm,+/-1%,1/16W,G,SMD0402 | PANASONIC INDUSTRIAL CO.,LTD. | ERJ2RKF1002X |  | G |  |  |  |  |  |  |  |
| Multi | ND | ND | ND | 124 | 124 | 610108U00-017-G |  | RES,10KOhm,+/-1%,1/10W,G,SMD0603 | KOA SPEER ELECTRONICS, INC. | RK73H1JTTD1002F | 10 | G | PAAR70,PBAR71,PBER72,PAFR72,PAER72,PBFR73,PBMR74,PAMR74,PBAR77,PAAR77 |  |  |  |  |  |  |
|  |  |  |  |  | 124 | 610108U00-024-G |  | RES,10KOhm,+/-1%,1/10W,G,SMD0603 | PANASONIC INDUSTRIAL CO.,LTD. | ERJ3EKF1002V |  | G |  |  |  |  |  |  |  |
| Single | ND | ND | ND | 125 | 125 | 610100C00-017-G |  | RES,15kOhm,+/-1%,1/10W,G,SMD0603 | KOA SPEER ELECTRONICS, INC. | RK73H1JTTD1502F | 2 | G | PBAR80,PAAR80 |  |  |  |  |  |  |
| Multi | ND | ND | Y(4) | 126 | 126 | 61011A500-017-G |  | RES,1.74KOhm,+/-1%,1/16W,G,SMD0402 | KOA SPEER ELECTRONICS, INC. | RK73H1ETTP1741F | 8 | G | PBMR81,PAMR81,PBER83,PAFR83,PAER83,PBFR84,PBAR84,PAAR84 |  |  |  |  |  |  |
|  |  |  |  |  | 126 | 61011A500-024-G |  | RES,1.74KOhm,+/-1%,1/16W,G,SMD0402 | PANASONIC INDUSTRIAL CO.,LTD. | ERJ2RKF1741X |  | G |  |  |  |  |  |  |  |
| Multi | N |  | Y(5) | 127 | 127 | 61100LR00-017-G |  | RES,100 Ohm,+/-1%,1/16W,G,SMD0402 | KOA SPEER ELECTRONICS, INC. | RN731ETTP1000F50 | 34 | G | PSPR6,PIPR6,PFPR6,PEPR6,PALR14,PALR15,PALR19,PBLR20,PALR20,PBLR21,PBLR23,PBLR24,PBER68,PBMR82,PAMR82,PBAR85,PAAR85,PAFR87,PAER87,PBFR88,PBMR91,PAMR91,PBAR93,PAAR93,PBMR94,PAMR94,PBAR96,PAAR96,R1265,R1269,R1273,R1277,R1484,R1745 |  |  |  |  |  |  |
|  |  |  |  |  | 127 | 61100YS00-029-G |  | RES,thin film,100Ohm,+/-1%,1/10W,SMD0402,G | VISHAY ENTER TECHNO LOGY.INC | MCS04020C1000FE000 |  | G |  |  |  |  |  |  |  |
| Multi | N | other | Y(4) | 128 | 128 | 61010CB00-017-G |  | RES,49.9 Ohm,+/-1%,1/10W,G,SMD0603 | KOA SPEER ELECTRONICS, INC. | RK73H1JTTD49R9F | 8 | G | PBER85,PAFR85,PBMR86,PBFR86,PBAR86,PAMR86,PAAR86,PAER672 |  |  |  |  |  |  |
|  |  |  |  |  | 128 | 61010CB00-024-G |  | RES,49.9 Ohm,+/-1%,1/10W,G,SMD0603 | PANASONIC INDUSTRIAL CO.,LTD. | ERJ3EKF49R9V |  | G |  |  |  |  |  |  |  |
| Multi | N | Other | Y(4) | 129 | 129 | 610130Y00-017-G |  | RES,1 Ohm,+/-1%,1/3W,G,SMD1206 | KOA SPEER ELECTRONICS, INC. | SR732BTTD1R00F | 11 | G | PHAR4,PBMR90,PAMR90,PBER92,PBAR92,PAFR92,PAER92,PAAR92,PBFR93,PBAR102,PAAR102 |  |  |  |  |  |  |
|  |  |  |  |  | 129 | 610606F00-029-G |  | RES,1 Ohm,+/-1%,1/3W,G,SMD1206 | VISHAY ENTER TECHNO LOGY.INC | L1206K1R00FNT |  | G |  |  |  |  |  |  |  |
| Multi | ND | ND | Y(5) | 130 | 130 | 611003200-017-G |  | RES,10KOhm,+/-0.1%,1/16W,G,SMD0402 | KOA SPEER ELECTRONICS, INC. | RN731ETTP1002B25 | 34 | G | PBMR26,PAMR26,PBMR97,PAMR97,PBMR98,PAMR98,PBER99,PAFR99,PAER99,PBMR100,PBFR100,PBER100,PAMR100,PAFR100,PAER100,PBFR101,PBMR102,PBER102,PAMR102,PAFR102,PAER102,PBFR103,PBAR103,PAAR103,PBER104,PBAR104,PAFR104,PAER104,PAAR104,PBFR105,PBAR106,PAAR106,PBAR108,PAAR108 |  |  |  |  |  |  |
|  |  |  |  |  | 130 | 611003200-024-G |  | RES,10KOhm,+/-0.1%,1/16W,G,SMD0402 | PANASONIC INDUSTRIAL CO.,LTD. | ERA2AEB103X |  | G |  |  |  |  |  |  |  |
| Multi | N | ND | ND | 131 | 131 | 61100M100-017-G |  | RES,4.75KOhm,+/-1%,1/16W,G,SMD0402 | KOA SPEER ELECTRONICS, INC. | RN731ETTP4751F50 | 2 | G | PBAR109,PAAR109 |  |  |  |  |  |  |
|  |  |  |  |  | 131 | 61100M100-011-G |  | RES,4.75KOhm,+/-1%,1/16W,G,SMD0402 | YAGEO CORPORATION COMPONENT | RT0402FRE074K75L |  | G |  |  |  |  |  |  |  |
| Multi | N | Other | Y(4) | 132 | 132 | 61011B300-017-G |  | RES,1MOhm,+/-1%,1/16W,G,SMD0402 | KOA SPEER ELECTRONICS, INC. | RK73H1ETTP1004F | 9 | G | PBMR107,PAMR107,PBER109,PAFR109,PAER109,PBFR110,PBAR113,PAAR113,R1844 |  |  |  |  |  |  |
|  |  |  |  |  | 132 | 61011B300-029-G |  | RES,1MOhm,+/-1%,1/16W,G,SMD0402 | VISHAY ENTER TECHNO LOGY.INC | CRCW04021M00FKED |  | G |  |  |  |  |  |  |  |
| Multi | ND |  | Y(4) | 133 | 133 | 61011GU00-017-G |  | RES,274 Ohm,+/-1%,1/16W,G,SMD0402 | KOA SPEER ELECTRONICS, INC. | RK73H1ETTP2740F | 8 | G | PBMR109,PAMR109,PBER111,PAFR111,PAER111,PBFR112,PBAR115,PAAR115 |  |  |  |  |  |  |
|  |  |  |  |  | 133 | 61011GU00-029-G |  | RES,274 Ohm,+/-1%,1/16W,G,SMD0402 | VISHAY ENTER TECHNO LOGY.INC | CRCW0402274RFKED |  | G |  |  |  |  |  |  |  |
| Multi | N |  | Y(5) | 134 | 134 | 61100RU00-017-G |  | RES,59 Ohm,+/-1%,1/16W,G,SMD0402 | KOA SPEER ELECTRONICS, INC. | RN731ETTP59R0F25 | 8 | G | PBMR113,PAMR113,PBER115,PAFR115,PAER115,PBFR116,PBAR119,PAAR119 |  |  |  |  |  |  |
|  |  |  |  |  | 134 | 611010300-029-G |  | RES,59 Ohm,+/-1%,1/10W,G,SMD0402 | VISHAY ENTER TECHNO LOGY.INC | TNPW040259R0FEEP |  | G |  |  |  |  |  |  |  |
| Multi | ND | ND | Y(4) | 135 | 135 | 610114P00-017-G |  | RES,715 Ohm,+/-1%,1/16W,G,SMD0402 | KOA SPEER ELECTRONICS, INC. | RK73H1ETTP7150F | 8 | G | PBMR117,PAMR117,PBER119,PAFR119,PAER119,PBFR120,PBAR123,PAAR123 |  |  |  |  |  |  |
|  |  |  |  |  | 135 | 610114P00-024-G |  | RES,715 Ohm,+/-1%,1/16W,G,SMD0402 | PANASONIC INDUSTRIAL CO.,LTD. | ERJ2RKF7150X |  | G |  |  |  |  |  |  |  |
| Multi | ND | ND | Y(4) | 136 | 136 | 61011L200-017-G |  | RES,3.65KOhm,+/-1%,1/16W,G,SMD0402 | KOA SPEER ELECTRONICS, INC. | RK73H1ETTP3651F | 9 | G | PHAR79,PBMR118,PAMR118,PBER120,PAFR120,PAER120,PBFR121,PBAR124,PAAR124 |  |  |  |  |  |  |
|  |  |  |  |  | 136 | 61011L200-029-G |  | RES,3.65KOhm,+/-1%,1/16W,G,SMD0402 | VISHAY ENTER TECHNO LOGY.INC | CRCW04023K65FKEDC |  | G |  |  |  |  |  |  |  |
| Multi | ND | ND | Y(4) | 137 | 137 | 61011BH00-017-G |  | RES,22.1 Ohm,+/-1%,1/16W,G,SMD0402 | KOA SPEER ELECTRONICS, INC. | RK73H1ETTP22R1F | 4 | G | PBMR304,PBAR304,PAMR304,PAAR304 |  |  |  |  |  |  |
|  |  |  |  |  | 137 | 61011BH00-024-G |  | RES,22.1 Ohm,+/-1%,1/16W,G,SMD0402 | PANASONIC INDUSTRIAL CO.,LTD. | ERJ2RKF22R1X |  | G |  |  |  |  |  |  |  |
|  |  |  |  |  | 137 | 61011BH00-029-G |  | RES,22.1 Ohm,+/-1%,1/16W,G,SMD0402 | VISHAY ENTER TECHNO LOGY.INC | CRCW040222R1FKED |  | G |  |  |  |  |  |  |  |
| Multi | ND |  | Y(4) | 138 | 138 | 61012JH00-017-G |  | RES,470 Ohm,+/-5%,1/8W,G,SMD0805 | KOA SPEER ELECTRONICS, INC. | RK73B2ATTD471J | 37 | G | PUAR13,PSAR13,PRAR13,PQAR13,PPAR13,PIAR13,PFAR13,PEAR13,PSIR14,PETR14,PERR14,PALR18,PSTR20,PSLR20,PSFR20,PSER20,PSDR20,PQPR20,PFRR20,PEER20,PEDR20,PBLR22,PBMR452,PBNR502,PBFR502,PBER502,PANR502,PAMR502,PAFR502,PAAR502,PBAR504,PAER514,PSPR3000,PIPR3000,PFPR3000,PEPR3000,PSRR3009 |  |  |  |  |  |  |
|  |  |  |  |  | 138 | 61012JH00-011-G |  | RES,470 Ohm,+/-5%,1/8W,G,SMD0805 | YAGEO CORPORATION COMPONENT | RC0805JR-07470RL |  | G |  |  |  |  |  |  |  |
|  |  |  |  |  | 138 | 61012JH00-044-G |  | RES,470 Ohm,+/-5%,1/8W,G,SMD0805 | TA-I TECHNOLOGY CO., LTD. | RM10JTN471 |  | G |  |  |  |  |  |  |  |
| Multi | N | ND | Y(4) | 139 | 139 | 610114J00-017-G |  | RES,2KOhm,+/-1%,1/16W,G,SMD0402 | KOA SPEER ELECTRONICS, INC. | RK73H1ETTP2001F | 11 | G | R347,R348,R350,PBFR510,PBER510,PAFR510,PAER510,PBMR600,PBAR600,PAMR600,PAAR600 |  |  |  |  |  |  |
|  |  |  |  |  | 139 | 610114J00-024-G |  | RES,2KOhm,+/-1%,1/16W,G,SMD0402 | PANASONIC INDUSTRIAL CO.,LTD. | ERJ2RKF2001X |  | G |  |  |  |  |  |  |  |
|  |  |  |  |  | 139 | 610114J00-029-G |  | RES,2KOhm,+/-1%,1/16W,G,SMD0402 | VISHAY ENTER TECHNO LOGY.INC | CRCW04022K00FKED |  | G |  |  |  |  |  |  |  |
| Multi | ND | ND | Y(4) | 140 | 140 | 61010L100-017-G |  | RES,100KOhm,+/-1%,1/16W,G,SMD0402 | KOA SPEER ELECTRONICS, INC. | RK73H1ETTP1003F | 17 | G | PBFR511,PBER511,PAFR511,PAER511,PBMR603,PBAR603,PAMR603,PAAR603,PBMR604,PBAR604,PAMR604,PAAR604,PAFR634,PBFR659,PBER659,PAER684,R1559 |  |  |  |  |  |  |
|  |  |  |  |  | 140 | 61010L106-029-G |  | RES,100KOhm,+/-1%,1/16W,G,SMD0402 | VISHAY ENTER TECHNO LOGY.INC | CRCW0402100KFKEDC |  | G |  |  |  |  |  |  |  |
|  |  |  |  |  | 140 | 61010L100-024-G |  | RES,100KOhm,+/-1%,1/16W,G,SMD0402 | PANASONIC INDUSTRIAL CO.,LTD. | ERJ2RKF1003X |  | G |  |  |  |  |  |  |  |
| Multi | ND |  | Y(4) | 141 | 141 | 61013A200-017-G |  | RES,6.8 Ohm,+/-1%,1/4W,G,SMD1206 | KOA SPEER ELECTRONICS, INC. | RK73H2BTTD6R80F | 4 | G | PBMR605,PBAR605,PAMR605,PAAR605 |  |  |  |  |  |  |
|  |  |  |  |  | 141 | 61013A200-029-G |  | RES,6.8 Ohm,+/-1%,1/4W,G,SMD1206 | VISHAY ENTER TECHNO LOGY.INC | CRCW12066R80FKEA |  | G |  |  |  |  |  |  |  |
| Multi | ND | ND | Y(4) | 142 | 142 | 61011MG00-017-G |  | RES,42.2KOhm,+/-1%,1/16W,G,SMD0402 | KOA SPEER ELECTRONICS, INC. | RK73H1ETTP4222F | 8 | G | PBFR512,PBER512,PAFR512,PAER512,PBMR606,PBAR606,PAMR606,PAAR606 |  |  |  |  |  |  |
|  |  |  |  |  | 142 | 61011MG00-011-G |  | RES,42.2KOhm,+/-1%,1/16W,G,SMD0402 | YAGEO CORPORATION COMPONENT | RC0402FR-0742K2L |  | G |  |  |  |  |  |  |  |
|  |  |  |  |  | 142 | 61011MG00-044-G |  | RES,42.2KOhm,+/-1%,1/16W,G,SMD0402 | TA-I TECHNOLOGY CO., LTD. | RM04FTN4222 |  | G |  |  |  |  |  |  |  |
| Single | ND | ND | Y(1) | 143 | 143 | 32040FG00-183-G |  | IC,Current Sensor,INA193AIDBVR,G,SOT23-5,SMD | TEXAS INSTRUMENTS | INA193AIDBVR | 8 | G | PBMU2,PBFU2,PBEU2,PBAU2,PAMU2,PAFU2,PAEU2,PAAU2 |  |  |  |  |  |  |
| Sole | N |  | N | 144 | 144 | 32014E200-53N-G |  | IC,Regulator,PI3753-00-LGIZ,ADJ,10.3A,G,LGA-108,SMD | Vicor Corporation | PI3753-00-LGIZ | 2 | G | PBAU3,PAAU3 |  |  |  |  |  |  |
| Sole | N |  | N | 145 | 145 | 880302200-53N-G |  | Converter,input 0V~60V,185W,G,VTM48MP012T130AA0 | Vicor Corporation | VTM48MP012T130AA0 | 4 | G | PBAU4,PAAU4,PBAU6,PAAU6 |  |  |  |  |  |  |
| Sole | N |  | Y(3) | 146 | 146 | 32031MS00-183-G |  | IC,Operation Amplifier,OPA2365AIDR,G,SOIC-8,SMD | TEXAS INSTRUMENTS | OPA2365AIDR | 8 | G | PBMU5,PBFU5,PBEU5,PAMU5,PAFU5,PAEU5,PBAU7,PAAU7 |  |  |  |  |  |  |
| Single | ND | ND | Y(3) | 147 | 147 | 620108600-015-G |  | CAP,180pF,+/-5%,NPO(C0G),50V,G,SMD0402 | MURATA ELEC. NORTH AMERICA | GRM1555C1H181J | 4 | G | PBFC4,PBEC4,PAFC4,PAEC4 |  |  |  |  |  |  |
| Multi | N | ND | Y(3) | 148 | 148 | 62010WW01-015-G |  | CAP,1.8nF,+/-10%,X7R,50V,G,SMD0402 | MURATA ELEC. NORTH AMERICA | GRM155R71H182KA01D | 4 | G | PBFC59,PBEC59,PAFC59,PAEC59 |  |  |  |  |  |  |
|  |  |  |  |  | 148 | 62010WW00-026-G |  | CAP,1.8nF,+/-10%,X7R,50V,G,SMD0402 | SAMSUNG SEMICONDUCTOR | CL05B182KB5NNNC |  | G |  |  |  |  |  |  |  |
| Multi | Y | 2 | Y(3) | 149 | 149 | 62011FQ00-015-G |  | CAP,5.6nF,+/-10%,X7R,50V,G,SMD0402 | MURATA ELEC. NORTH AMERICA | GRM155R71H562K | 6 | G | PBFC60,PBEC60,PAFC60,PAEC60,PBMC61,PAMC61 |  |  |  |  |  |  |
|  |  |  |  |  | 149 | 62011FQ00-026-G |  | CAP,5.6nF,+/-10%,X7R,50V,G,SMD0402 | SAMSUNG SEMICONDUCTOR | CL05B562KB5NNNC |  | G |  |  |  |  |  |  |  |
|  |  |  |  |  | 149 | 62011FQ00-023-G |  | CAP,5.6nF,+/-10%,X7R,50V,G,SMD0402 | TAIYO ELECTRIC IND.CO.LTD | UMK105B7562KV-F |  | G |  |  |  |  |  |  |  |
| Multi | N |  | N | 150 | 150 | 63035NF00-57M-G |  | IND,1.5uH@100KHz,+/-10%,12A,6mOhm,SHLD,G,SMD | Eaton Corporation | HCV1206-1R5-R | 6 | G | PBFL1,PBEL1,PAFL1,PAEL1,PBML2,PAML2 |  |  |  |  |  |  |
|  |  |  |  |  | 150 | 630362H00-065-G |  | IND,1.5uH@100KHz,+/-10%,12A,6.6mOhm,SHLD,G,SMD | DELTA ELECTRONICS INDUSTRIAL CO.,LTD | HMS1360-1R5 |  | G |  |  |  |  |  |  |  |
| Multi | ND |  | Y(4) | 151 | 151 | 610117V00-017-G |  | RES,680 Ohm,+/-1%,1/16W,G,SMD0402 | KOA SPEER ELECTRONICS, INC. | RK73H1ETTP6800F | 4 | G | PBER4,PAER4,R972,R1090 |  |  |  |  |  |  |
|  |  |  |  |  | 151 | 610117V00-011-G |  | RES,680 Ohm,+/-1%,1/16W,G,SMD0402 | YAGEO CORPORATION COMPONENT | RC0402FR-07680RL |  | G |  |  |  |  |  |  |  |
|  |  |  |  |  | 151 | 610117V00-044-G |  | RES,680 Ohm,+/-1%,1/16W,G,SMD0402 | TA-I TECHNOLOGY CO., LTD. | RM04FTN6800 |  | G |  |  |  |  |  |  |  |
| Multi | ND |  | Y(5) | 152 | 152 | 61100RN00-017-G |  | RES,15.4KOhm,+/-0.1%,1/16W,G,SMD0402 | KOA SPEER ELECTRONICS, INC. | RN731ETTP1542B25 | 4 | G | PBFR26,PBER26,PAFR26,PAER26 |  |  |  |  |  |  |
|  |  |  |  |  | 152 | 61100RN00-011-G |  | RES,15.4KOhm,+/-0.1%,1/16W,G,SMD0402 | YAGEO CORPORATION COMPONENT | RT0402BRD0715K4L |  | G |  |  |  |  |  |  |  |
|  |  |  |  |  | 152 | 61100RN00-044-G |  | RES,15.4KOhm,+/-0.1%,1/16W,G,SMD0402 | TA-I TECHNOLOGY CO., LTD. | RB04BTP1542 |  | G |  |  |  |  |  |  |  |
| Single | N |  | Y(4) | 153 | 153 | 61100YT00-017-G |  | RES,487 Ohm,+/-0.1%,1/16W,G,SMD0402 | KOA SPEER ELECTRONICS, INC. | RN731ETTP4870B25 | 4 | G | PBFR34,PBER34,PAFR34,PAER34 |  |  |  |  |  |  |
| Multi | N | ND | Y(4) | 154 | 154 | 61011DR00-017-G |  | RES,2.2KOhm,+/-1%,1/16W,G,SMD0402 | KOA SPEER ELECTRONICS, INC. | RK73H1ETTP2201F | 18 | G | PBFR47,PBER47,PAFR47,PAER47,R781,R782,R1726,R1727,R1728,R1730,R1731,R1732,R1734,R1735,R1736,R1738,R1739,R1740 |  |  |  |  |  |  |
|  |  |  |  |  | 154 | 61011DR00-029-G |  | RES,2.2KOhm,+/-1%,1/16W,G,SMD0402 | VISHAY ENTER TECHNO LOGY.INC | CRCW04022K20FKED |  | G |  |  |  |  |  |  |  |
| Single | ND |  | Y(4) | 155 | 155 | 610127L00-017-G |  | RES,215 Ohm,+/-1%,1/16W,G,SMD0402 | KOA SPEER ELECTRONICS, INC. | RK73H1ETTP2150F | 4 | G | PBFR57,PBER57,PAFR57,PAER57 |  |  |  |  |  |  |
| Multi | ND | ND | Y(4) | 156 | 156 | 610108V00-017-G |  | RES,2KOhm,+/-1%,1/10W,G,SMD0603 | KOA SPEER ELECTRONICS, INC. | RK73H1JTTD2001F | 6 | G | PBER58,PAFR58,PAER58,PBFR59,PBMR61,PAMR61 |  |  |  |  |  |  |
|  |  |  |  |  | 156 | 610108V00-024-G |  | RES,2KOhm,+/-1%,1/10W,G,SMD0603 | PANASONIC INDUSTRIAL CO.,LTD. | ERJ3EKF2001V |  | G |  |  |  |  |  |  |  |
| Multi | ND |  | N | 157 | 157 | 610606H00-017-G |  | RES,50mOhm,+/-1%,1.5W,G,SMD2512 | KOA | SLW1TTE50L0F | 4 | G | PBER65,PAFR65,PAER65,PBFR66 |  |  |  |  |  |  |
|  |  |  |  |  | 157 | 610606E00-125-G |  | RES,50mOhm,+/-1%,1W,G,SMD2512 | INTERNATIONAL RESISTIVE COMPANY, INC. | LRMAP2512-R05FT4 |  | G |  |  |  |  |  |  |  |
| Multi | ND | ND | Y(4) | 158 | 158 | 61010RW00-017-G |  | RES,23.2KOhm,+/-1%,1/10W,G,SMD0603 | KOA SPEER ELECTRONICS, INC. | RK73H1JTTD2322F | 8 | G | PBER66,PAFR66,PAER66,PBFR67,PBER67,PAFR67,PAER67,PBFR68 |  |  |  |  |  |  |
|  |  |  |  |  | 158 | 61010RW00-029-G |  | RES,23.2KOhm,+/-1%,1/10W,G,SMD0603 | VISHAY ENTER TECHNO LOGY.INC | CRCW060323K2FKEA |  | G |  |  |  |  |  |  |  |
|  |  |  |  |  | 158 | 61010RW00-024-G |  | RES,23.2KOhm,+/-1%,1/10W,G,SMD0603 | PANASONIC INDUSTRIAL CO.,LTD. | ERJ3EKF2322V |  | G |  |  |  |  |  |  |  |
| Single | N | Other | Y(4) | 159 | 159 | 610107K00-017-G |  | RES,24.9KOhm,+/-1%,1/10W,G,SMD0603 | KOA SPEER ELECTRONICS, INC. | RK73H1JTTD2492F | 4 | G | PBER84,PAFR84,PAER84,PBFR85 |  |  |  |  |  |  |
| Multi | ND |  | Y(4) | 160 | 160 | 61015NJ00-017-G |  | RES,6.04 Ohm,+/-1%,1/4W,G,SMD1206 | KOA SPEER ELECTRONICS, INC. | RK73H2BTTD6R04F | 4 | G | PBFR513,PBER513,PAFR513,PAER513 |  |  |  |  |  |  |
|  |  |  |  |  | 160 | 61015NJ00-011-G |  | RES,6.04 Ohm,+/-1%,1/4W,G,SMD1206 | YAGEO CORPORATION COMPONENT | RC1206FR-076R04L |  | G |  |  |  |  |  |  |  |
|  |  |  |  |  | 160 | 61015NJ00-044-G |  | RES,6.04 Ohm,+/-1%,1/4W,G,SMD1206 | TA-I TECHNOLOGY CO., LTD. | RM12FTN6R04 |  | G |  |  |  |  |  |  |  |
| Sole | N |  | N | 161 | 161 | 32014CE00-53N-G |  | IC,Regulator,PI3755-02-LGIZ,ADJ,4A,G,LGA-71,SMD | Vicor Corporation | PI3755-02-LGIZ | 6 | G | PBMU3,PBFU3,PBEU3,PAMU3,PAFU3,PAEU3 |  |  |  |  |  |  |
| Sole | N | ND | N | 162 | 162 | 880302600-53N-G |  | Converter,input 0V~52V,120W,G,VTM48RP015C076AG0 | Vicor Corporation | VTM48RP015C076AG0 | 4 | G | PBFU4,PBEU4,PAFU4,PAEU4 |  |  |  |  |  |  |
| Multi | N | Other | Y(4) | 163 | 163 | 610117U00-017-G |  | RES,820 Ohm,+/-1%,1/16W,G,SMD0402 | KOA SPEER ELECTRONICS, INC. | RK73H1ETTP8200F | 2 | G | PBFR3,PAFR3 |  |  |  |  |  |  |
|  |  |  |  |  | 163 | 610117U00-011-G |  | RES,820 Ohm,+/-1%,1/16W,G,SMD0402 | YAGEO CORPORATION COMPONENT | RC0402FR-07820RL |  | G |  |  |  |  |  |  |  |
|  |  |  |  |  | 163 | 610117U00-044-G |  | RES,820 Ohm,+/-1%,1/16W,G,SMD0402 | TA-I TECHNOLOGY CO., LTD. | RM04FTN8200 |  | G |  |  |  |  |  |  |  |
| Multi | Y | 2 | Y(3) | 164 | 164 | 620109700-015-G |  | CAP,3.3nF,+/-10%,X7R,50V,G,SMD0402 | MURATA ELEC. NORTH AMERICA | GRM155R71H332K | 21 | G | PIPC10,PFPC10,PEPC10,PBNC11,PANC11,PBNC13,PANC13,PUAC18,PSAC18,PRAC18,PQAC18,PPAC18,PIAC18,PFAC18,PEAC18,PBNC25,PANC25,PALC35,PALC40,PBLC56,PBLC60 |  |  |  |  |  |  |
|  |  |  |  |  | 164 | 620109700-026-G |  | CAP,3.3nF,+/-10%,X7R,50V,G,SMD0402 | SAMSUNG SEMICONDUCTOR | CL05B332KB5NNNC |  | G |  |  |  |  |  |  |  |
|  |  |  |  |  | 164 | 620109700-023-G |  | CAP,3.3nF,+/-10%,X7R,50V,G,SMD0402 | TAIYO ELECTRIC IND.CO.LTD | UMK105B7332KV-F |  | G |  |  |  |  |  |  |  |
| Multi | Y |  | Y(1) | 165 | 165 | 620131D00-015-G |  | CAP,1uF,+/-10%,X6S,16V,G,SMD0402 | MURATA ELEC. NORTH AMERICA | GRM155C81C105KE11J | 6 | G | PHAC1,PANC1,PBNC2,PHAC7,PALC37,PBLC62 |  |  |  |  |  |  |
|  |  |  |  |  | 165 | 620131D00-023-G |  | CAP,1uF,+/-10%,X6S,16V,G,SMD0402 | TAIYO ELECTRIC IND.CO.LTD | EMK105C6105KV-F |  | G |  |  |  |  |  |  |  |
| Sole | N |  | Y(3) | 166 | 166 | 62012GG00-015-G |  | CAP,10uF,+/-10%,X7S,25V,G,SMD0805 | MURATA ELEC. NORTH AMERICA | GRM21BC71E106K | 68 | G | PSTC2,PSLC2,PSFC2,PSEC2,PSDC2,PQPC2,PFRC2,PEEC2,PEDC2,PANC2,PSTC3,PSLC3,PSFC3,PSEC3,PSDC3,PQPC3,PFRC3,PEEC3,PEDC3,PBNC3,PANC3,PBNC4,PANC4,PBNC5,PANC5,PSPC6,PIPC6,PFPC6,PEPC6,PBNC6,PSPC7,PIPC7,PFPC7,PEPC7,PSPC8,PIPC8,PFPC8,PEPC8,PSPC9,PIPC9,PFPC9,PEPC9,PSTC17,PSTC18,PALC38,PALC39,PBLC54,PBLC55,PSPC3004,PIPC3004,PFPC3004,PEPC3004,PSPC3005,PIPC3005,PFPC3005,PEPC3005,PSPC3006,PIPC3006,PFPC3006,PEPC3006,PSPC3007,PIPC3007,PFPC3007,PEPC3007,PSPC3009,PIPC3009,PFPC3009,PEPC3009 |  |  |  |  |  |  |
| Multi | N |  | N | 167 | 167 | 72010RE00-015-G |  | FB,26 Ohm@100MHz,+/-25%,6A,7mOhm,G,SMD0603 | MURATA ELEC. NORTH AMERICA | BLM18KG260TN1D | 22 | G | PSTL1,PSLL1,PSFL1,PSEL1,PSDL1,PQPL1,PFRL1,PEEL1,PEDL1,PBLL1,PALL1,PUAL2,PSIL2,PSAL2,PRAL2,PQAL2,PPAL2,PIAL2,PFAL2,PERL2,PEAL2,PQPL3 |  |  |  |  |  |  |
|  |  |  |  |  | 167 | 72010SJ00-059-G |  | FB,26 Ohm@100MHz,+/-25%,6A,10mOhm,G,SMD0603 | TAI-TECH ADVANCED ELECTRONICS CO., LTD. | HCB1608KF-260T60 |  | G |  |  |  |  |  |  |  |
| Multi | ND |  | N | 168 | 168 | 630351600-034-G |  | IND,470nH@100KHz,+/-20%,30A,1.68mOhm,SHLD,G,SMD | CYNTEC CO. LTD | PCMB104T-R47MS | 2 | G | PALL2,PBLL4 |  |  |  |  |  |  |
|  |  |  |  |  | 168 | 63035YA00-051-G |  | IND,470nH@100KHz,+/-20%,28A,1.5mOhm,SHLD,G,SMD | PULSE ELECTRONICS (SINGAPORE) | PA4342.471NLT |  | G |  |  |  |  |  |  |  |
|  |  |  |  |  | 168 | 63035Y900-129-G |  | IND,470nH@100KHz,+/-20%,30A,1.68mOhm,SHLD,G,SMD | MAG.LAYERS, SCIENTIFIC-TECHNICS (KUNSHAN) CO., LTD. | SPS-10DZ-R47M-X2 |  | G |  |  |  |  |  |  |  |
| Sole | N |  | N | 169 | 169 | 320244200-230-G |  | IC,PWM Controller,ISL99227FRZ-T,G,QFN-32,SMD | INTERSIL CORPORATION | ISL99227FRZ-T | 2 | G | PALU1,PBLU3 |  |  |  |  |  |  |
| Single | Y | 2 | Y(3) | 170 | 170 | 62010BH00-015-G |  | CAP,220pF,+/-5%,NPO(C0G),50V,G,SMD0402 | MURATA ELEC. NORTH AMERICA | GRM1555C1H221J | 2 | G | PBMC4,PAMC4 |  |  |  |  |  |  |
| Multi | ND | ND | Y(4) | 171 | 171 | 61011QD00-017-G |  | RES,330 Ohm,+/-1%,1/16W,G,SMD0402 | KOA SPEER ELECTRONICS, INC. | RK73H1ETTP3300F | 2 | G | PBMR3,PAMR12 |  |  |  |  |  |  |
|  |  |  |  |  | 171 | 61011QD00-029-G |  | RES,330 Ohm,+/-1%,1/16W,G,SMD0402 | VISHAY ENTER TECHNO LOGY.INC | CRCW0402330RFKED |  | G |  |  |  |  |  |  |  |
| Single | ND |  | Y(5) | 172 | 172 | 61100YW00-017-G |  | RES,316 Ohm,+/-0.1%,1/16W,G,SMD0402 | KOA SPEER ELECTRONICS, INC. | RN731ETTP3160B25 | 2 | G | PBMR34,PAMR34 |  |  |  |  |  |  |
| Multi | ND |  | Y(4) | 173 | 173 | 61011HT00-017-G |  | RES,1.8KOhm,+/-1%,1/16W,G,SMD0402 | KOA SPEER ELECTRONICS, INC. | RK73H1ETTP1801F | 2 | G | PBMR47,PAMR47 |  |  |  |  |  |  |
|  |  |  |  |  | 173 | 61011HT00-029-G |  | RES,1.8KOhm,+/-1%,1/16W,G,SMD0402 | VISHAY ENTER TECHNO LOGY.INC | CRCW04021K80FKED |  | G |  |  |  |  |  |  |  |
|  |  |  |  |  | 173 | ERA2RKF1801X |  | RES,1.8KOhm,+/-1%,1/16W,G,SMD0402 | PANASONIC INDUSTRIAL CO.,LTD. | ERA2RKF1801X |  | G |  |  |  |  |  |  |  |
| Single | ND | ND | Y(4) | 174 | 174 | 610119U00-017-G |  | RES,133 Ohm,+/-1%,1/16W,G,SMD0402 | KOA SPEER ELECTRONICS, INC. | RK73H1ETTP1330F | 2 | G | PBMR57,PAMR57 |  |  |  |  |  |  |
| Multi | ND |  | N | 175 | 175 | 610606J00-017-G |  | RES,75mOhm,+/-1%,1.5W,G,SMD2512 | KOA | SLW1TTE75L0F | 2 | G | PBMR65,PAMR65 |  |  |  |  |  |  |
|  |  |  |  |  | 175 | 610606D00-125-G |  | RES,75mOhm,+/-1%,1W,G,SMD2512 | INTERNATIONAL RESISTIVE COMPANY, INC. | LRMAP2512-R075FT4 |  | G |  |  |  |  |  |  |  |
| Single | ND | ND | Y(4) | 176 | 176 | 61010A700-017-G |  | RES,30.9KOhm,+/-1%,1/10W,G,SMD0603 | KOA SPEER ELECTRONICS, INC. | RK73H1JTTD3092F | 2 | G | PBMR77,PAMR77 |  |  |  |  |  |  |
| Single | N | ND | Y(4) | 177 | 177 | 61011FU00-017-G |  | RES,115KOhm,+/-1%,1/16W,G,SMD0402 | KOA SPEER ELECTRONICS, INC. | RK73H1ETTP1153F | 2 | G | PBMR121,PAMR121 |  |  |  |  |  |  |
| Sole | N |  | N | 178 | 178 | 880302800-53N-G |  | Converter,input 0V~60V,131W,G,VTM48MP010C105AG0 | Vicor Corporation | VTM48MP010C105AG0 | 2 | G | PBMU4,PAMU4 |  |  |  |  |  |  |
| Multi | ND | ND | N | 179 | 179 | 62010HR00-015-G |  | CAP,100nF,+/-10%,X7R,50V,G,SMD0603 | MURATA ELEC. NORTH AMERICA | GRM188R71H104K | 13 | G | PUAC8,PSIC8,PSAC8,PRAC8,PQAC8,PPAC8,PIAC8,PFAC8,PETC8,PERC8,PEAC8,PBNC10,PANC10 |  |  |  |  |  |  |
|  |  |  |  |  | 179 | 62010HR00-026-G |  | CAP,100nF,+/-10%,X7R,50V,G,SMD0603 | SAMSUNG SEMICONDUCTOR | CL10B104KB8NNNC |  | G |  |  |  |  |  |  |  |
| Multi | ND |  | N | 180 | 180 | 630330G00-088-G |  | IND,300nH@100KHz,+/-10%,32.5A,304.5uOhm,SHLD,G,SMD | COOPER BUSSMANN, INC. | FP0906R1-R30-R | 2 | G | PBNL1,PANL1 |  |  |  |  |  |  |
|  |  |  |  |  | 180 | 630332A01-051-G |  | Coil Ind,Shielded(SHLD),300nH@100KHz,+/-10%,34A,290uOhm,SMD,9.2*6.2*7.8,G | PULSE ELECTRONICS (SINGAPORE) | PA3288.301HLT |  | G |  |  |  |  |  |  |  |
|  |  |  |  |  | 180 | 630330G00-129-G |  | IND,300nH@100KHz,+/-10%,32.5A,290uOhm,SHLD,G,SMD | MAG.LAYERS, SCIENTIFIC-TECHNICS (KUNSHAN) CO., LTD. | MSI-900608-R30K-E |  | G |  |  |  |  |  |  |  |
| Multi | ND |  | Y(4) | 181 | 181 | 61011JH00-017-G |  | RES,19.1KOhm,+/-1%,1/16W,G,SMD0402 | KOA SPEER ELECTRONICS, INC. | RK73H1ETTP1912F | 6 | G | PANR6,PBNR7,R355,R356,R361,R362 |  |  |  |  |  |  |
|  |  |  |  |  | 181 | 61011JH00-011-G |  | RES,19.1KOhm,+/-1%,1/16W,G,SMD0402 | YAGEO CORPORATION COMPONENT | RC0402FR-0719K1L |  | G |  |  |  |  |  |  |  |
|  |  |  |  |  | 181 | 61011JH00-044-G |  | RES,19.1KOhm,+/-1%,1/16W,G,SMD0402 | TA-I TECHNOLOGY CO., LTD. | RM04FTN1912 |  | G |  |  |  |  |  |  |  |
| Multi | ND | ND | Y(4) | 182 | 182 | 610114S00-017-G |  | RES,4.99KOhm,+/-1%,1/16W,G,SMD0402 | KOA SPEER ELECTRONICS, INC. | RK73H1ETTP4991F | 3 | G | PFRR3,PBNR5,PANR7 |  |  |  |  |  |  |
|  |  |  |  |  | 182 | 610114S00-024-G |  | RES,4.99KOhm,+/-1%,1/16W,G,SMD0402 | PANASONIC INDUSTRIAL CO.,LTD. | ERJ2RKF4991X |  | G |  |  |  |  |  |  |  |
| Multi | ND | ND | Y(4) | 183 | 183 | 610114B00-017-G |  | RES,2.49KOhm,+/-1%,1/16W,G,SMD0402 | KOA SPEER ELECTRONICS, INC. | RK73H1ETTP2491F | 2 | G | PBNR11,PANR11 |  |  |  |  |  |  |
|  |  |  |  |  | 183 | 610114B00-024-G |  | RES,2.49KOhm,+/-1%,1/16W,G,SMD0402 | PANASONIC INDUSTRIAL CO.,LTD. | ERJ2RKF2491X |  | G |  |  |  |  |  |  |  |
|  |  |  |  |  | 183 | 610114B00-029-G |  | RES,2.49KOhm,+/-1%,1/16W,G,SMD0402 | VISHAY ENTER TECHNO LOGY.INC | CRCW04022K49FKED |  | G |  |  |  |  |  |  |  |
| Multi | N | Other | Y(4) | 184 | 184 | 61011CJ00-017-G |  | RES,365 Ohm,+/-1%,1/16W,G,SMD0402 | KOA SPEER ELECTRONICS, INC. | RK73H1ETTP3650F | 2 | G | PBNR14,PANR14 |  |  |  |  |  |  |
|  |  |  |  |  | 184 | 61011CJ00-024-G |  | RES,365 Ohm,+/-1%,1/16W,G,SMD0402 | PANASONIC INDUSTRIAL CO.,LTD. | ERJ2RKF3650X |  | G |  |  |  |  |  |  |  |
|  |  |  |  |  | 184 | 61011CJ00-029-G |  | RES,365 Ohm,+/-1%,1/16W,G,SMD0402 | VISHAY ENTER TECHNO LOGY.INC | CRCW0402365RFKEDC |  | G |  |  |  |  |  |  |  |
| Multi | ND | ND | Y(4) | 185 | 185 | 610112G00-017-G |  | RES,20 Ohm,+/-1%,1/16W,G,SMD0402 | KOA SPEER ELECTRONICS, INC. | RK73H1ETTP20R0F | 2 | G | PBNR15,PANR15 |  |  |  |  |  |  |
|  |  |  |  |  | 185 | 610112G00-024-G |  | RES,20 Ohm,+/-1%,1/16W,G,SMD0402 | PANASONIC INDUSTRIAL CO.,LTD. | ERJ2RKF20R0X |  | G |  |  |  |  |  |  |  |
| Multi | ND |  | Y(5) | 186 | 186 | 611005R00-017-G |  | RES,100 Ohm,+/-0.1%,1/16W,G,SMD0402 | KOA SPEER ELECTRONICS, INC. | RN731ETTP1000B25 | 5 | G | PSRR16,PBNR16,PANR16,PBNR18,PANR18 |  |  |  |  |  |  |
|  |  |  |  |  | 186 | 61100YM00-029-G |  | RES,100 Ohm,+/-0.1%,1/16W,G,SMD0402 | VISHAY ENTER TECHNO LOGY.INC | TNPW0402100RBEED |  | G |  |  |  |  |  |  |  |
| Multi | ND | ND | Y(4) | 187 | 187 | 61011B600-017-G |  | RES,5.36KOhm,+/-1%,1/16W,G,SMD0402 | KOA SPEER ELECTRONICS, INC. | RK73H1ETTP5361F | 2 | G | PBNR17,PANR17 |  |  |  |  |  |  |
|  |  |  |  |  | 187 | 61011B600-024-G |  | RES,5.36KOhm,+/-1%,1/16W,G,SMD0402 | PANASONIC INDUSTRIAL CO.,LTD. | ERJ2RKF5361X |  | G |  |  |  |  |  |  |  |
|  |  |  |  |  | 187 | 61011B600-029-G |  | RES,5.36KOhm,+/-1%,1/16W,G,SMD0402 | VISHAY ENTER TECHNO LOGY.INC | CRCW04025K36FKEDC |  | G |  |  |  |  |  |  |  |
| Multi | ND | ND | Y(4) | 188 | 188 | 61010LA00-017-G |  | RES,4.7KOhm,+/-1%,1/16W,G,SMD0402 | KOA SPEER ELECTRONICS, INC. | RK73H1ETTP4701F | 149 | G | PSRR20,PBNR23,PANR23,PHAR28,PHAR29,PHAR30,R762,R763,R764,R766,R767,R769,R770,R772,R773,R774,R775,R776,R777,R778,R779,R780,R783,R784,R786,R787,R788,R791,R795,R800,R801,R804,R805,R806,R807,R808,R809,R811,R814,R817,R820,R822,R823,R825,R827,R828,R830,R893,R894,R901,R902,R922,R942,R943,R944,R945,R949,R950,R955,R956,R957,R958,R959,R1129,R1135,R1138,R1148,R1149,R1150,R1151,R1152,R1156,R1159,R1162,R1164,R1165,R1172,R1174,R1175,R1176,R1184,R1185,R1186,R1190,R1195,R1197,R1198,R1199,R1210,R1211,R1212,R1213,R1218,R1219,R1220,R1221,R1222,R1223,R1224,R1256,R1257,R1263,R1267,R1271,R1275,R1295,R1296,R1461,R1463,R1464,R1465,R1467,R1469,R1470,R1471,R1474,R1475,R1476,R1477,R1495,R1504,R1507,R1508,R1509,R1511,R1512,R1515,R1520,R1521,R1550,R1551,R1558,R1589,R1590,R1592,R1593,R1603,R1604,R1605,R1606,R1779,R1780,R1781,R1782,R1789,R1801,R1820,R1821,R1834 |  |  |  |  |  |  |
|  |  |  |  |  | 188 | 61010LA00-029-G |  | RES,4.7KOhm,+/-1%,1/16W,G,SMD0402 | VISHAY ENTER TECHNO LOGY.INC | CRCW04024K70FKED |  | G |  |  |  |  |  |  |  |
| Multi | N | ND | Y(4) | 189 | 189 | 61011CS00-017-G |  | RES,750KOhm,+/-1%,1/16W,G,SMD0402 | KOA SPEER ELECTRONICS, INC. | RK73H1ETTP7503F | 2 | G | PBNR24,PANR24 |  |  |  |  |  |  |
|  |  |  |  |  | 189 | 61011CS00-011-G |  | RES,750KOhm,+/-1%,1/16W,G,SMD0402 | YAGEO CORPORATION COMPONENT | RC0402FR-07750KL |  | G |  |  |  |  |  |  |  |
|  |  |  |  |  | 189 | 61011CS00-029-G |  | RES,thick film,750KOhm,+/-1%,1/16W,SMD0402,G | VISHAY ENTER TECHNO LOGY.INC | CRCW0402750KFKED |  | G |  |  |  |  |  |  |  |
| Multi | ND | ND | Y(4) | 190 | 190 | 61011BS00-017-G |  | RES,2.05KOhm,+/-1%,1/16W,G,SMD0402 | KOA SPEER ELECTRONICS, INC. | RK73H1ETTP2051F | 1 | G | PANR26 |  |  |  |  |  |  |
|  |  |  |  |  | 190 | 61011BS00-029-G |  | RES,2.05KOhm,+/-1%,1/16W,G,SMD0402 | VISHAY ENTER TECHNO LOGY.INC | CRCW04022K05FKED |  | G |  |  |  |  |  |  |  |
| Multi | N | Other | Y(4) | 191 | 191 | 610118R00-017-G |  | RES,1.54KOhm,+/-1%,1/16W,G,SMD0402 | KOA SPEER ELECTRONICS, INC. | RK73H1ETTP1541F | 1 | G | PBNR26 |  |  |  |  |  |  |
|  |  |  |  |  | 191 | 610118R00-029-G |  | RES,1.54KOhm,+/-1%,1/16W,G,SMD0402 | VISHAY ENTER TECHNO LOGY.INC | CRCW04021K54FKED |  | G |  |  |  |  |  |  |  |
| Single | ND |  | N | 192 | 192 | 10061913-102HLF |  | CONN,PCIE-8X,V/T,Bla,1mm,30u,G,SMD-98 | FCI CONNECTORS HONGKONG LTD. | 10061913-102HLF | 2 | G | PCIE1,PCIE5 |  |  |  |  |  |  |
| Multi | ND |  | N | 193 | 193 | 10061913-103HLF |  | CONN,PCIE-16X,V/T,Bla,1mm,30u,G,SMD-164 | FCI CONNECTORS HONGKONG LTD. | 10061913-103HLF | 3 | G | PCIE2,PCIE3,PCIE4 |  |  |  |  |  |  |
|  |  |  |  |  | 193 | 340321600-278-G |  | CONN,PCIE-16X,V/T,Bla,1mm,30u,G,SMD-164 | TYCO ELECTRONICS CORPORATION | 2041366-9 |  | G |  |  |  |  |  |  |  |
| Multi | ND | ND | Y(1) | 194 | 194 | 62011F100-015-G |  | CAP,1uF,+/-10%,X7R,25V,G,SMD0603 | MURATA ELEC. NORTH AMERICA | GRM188R71E105K | 12 | G | PUAC1,PSIC1,PSAC1,PRAC1,PQAC1,PPAC1,PIAC1,PFAC1,PETC1,PERC1,PEAC1,PSUC4 |  |  |  |  |  |  |
|  |  |  |  |  | 194 | 62011F100-026-G |  | CAP,1uF,+/-10%,X7R,25V,G,SMD0603 | SAMSUNG SEMICONDUCTOR | CL10B105KA8NNNC |  | G |  |  |  |  |  |  |  |
|  |  |  |  |  | 194 | 62011F100-023-G |  | CAP,1uF,+/-10%,X7R,25V,G,SMD0603 | TAIYO ELECTRIC IND.CO.LTD | TMK107B7105KA-T |  | G |  |  |  |  |  |  |  |
| Multi | Y | 2 | Y(1) | 195 | 195 | 62011DD00-015-G |  | CAP,22uF,+/-10%,X6S,6.3V,G,SMD1206 | MURATA ELEC. NORTH AMERICA | GRM31CC80J226K | 24 | G | PUAC4,PSAC4,PRAC4,PQAC4,PPAC4,PIAC4,PFAC4,PEAC4,PUAC5,PSAC5,PRAC5,PQAC5,PPAC5,PIAC5,PFAC5,PEAC5,PUAC6,PSAC6,PRAC6,PQAC6,PPAC6,PIAC6,PFAC6,PEAC6 |  |  |  |  |  |  |
|  |  |  |  |  | 195 | 62011DD00-026-G |  | CAP,22uF,+/-10%,X6S,6.3V,G,SMD1206 | SAMSUNG SEMICONDUCTOR | CL31X226KQHNNNE |  | G |  |  |  |  |  |  |  |
| Multi | Y | ND | Y(1) | 196 | 196 | 620119R04-015-G |  | CAP,22uF,+/-20%,X6S,4V,G,SMD0805 | MURATA ELEC. NORTH AMERICA | GRM21BC80G226M | 84 | G | PSLC7,PSFC7,PSEC7,PSDC7,PEEC7,PEDC7,PSLC8,PSFC8,PSEC8,PSDC8,PEEC8,PEDC8,PUAC11,PSLC11,PSIC11,PSFC11,PSEC11,PSDC11,PSAC11,PRAC11,PQAC11,PPAC11,PIAC11,PFAC11,PEEC11,PEDC11,PEAC11,PUAC12,PSLC12,PSIC12,PSFC12,PSEC12,PSDC12,PSAC12,PRAC12,PQAC12,PPAC12,PIAC12,PFAC12,PEEC12,PEDC12,PEAC12,PUAC13,PSIC13,PSAC13,PRAC13,PQAC13,PPAC13,PIAC13,PFAC13,PEAC13,PUAC14,PSIC14,PSAC14,PRAC14,PQAC14,PPAC14,PIAC14,PFAC14,PEAC14,PUAC15,PSLC15,PSIC15,PSFC15,PSEC15,PSDC15,PSAC15,PRAC15,PQAC15,PPAC15,PIAC15,PFAC15,PEEC15,PEDC15,PEAC15,PUAC16,PSIC16,PSAC16,PRAC16,PQAC16,PPAC16,PIAC16,PFAC16,PEAC16 |  |  |  |  |  |  |
|  |  |  |  |  | 196 | 620119R00-023-G |  | CAP,22uF,+/-20%,X6S,4V,G,SMD0805 | TAIYO ELECTRIC IND.CO.LTD | AMK212C6226MG-T |  | G |  |  |  |  |  |  |  |
|  |  |  |  |  | 196 | 620119R00-026-G |  | CAP,22uF,+/-20%,X6S,4V,G,SMD0805 | SAMSUNG SEMICONDUCTOR | CL21X226MRQNNNE |  | G |  |  |  |  |  |  |  |
| Sole | N |  | Y(3) | 197 | 197 | 62012G600-015-G |  | CAP,2.2uF,+/-10%,X7S,25V,G,SMD0603 | MURATA ELEC. NORTH AMERICA | GRM188C71E225K | 11 | G | PUAC19,PSIC19,PSAC19,PRAC19,PQAC19,PPAC19,PIAC19,PFAC19,PETC19,PERC19,PEAC19 |  |  |  |  |  |  |
| Multi | ND |  | N | 198 | 198 | 630335M00-088-G |  | IND,820nH@100KHz,+/-20%,13A,8mOhm,SHLD,G,SMD | COOPER BUSSMANN, INC. | HCM0703-R82-R | 8 | G | PUAL1,PSAL1,PRAL1,PQAL1,PPAL1,PIAL1,PFAL1,PEAL1 |  |  |  |  |  |  |
|  |  |  |  |  | 198 | 63035Y800-051-G |  | IND,820nH@100KHz,+/-20%,13A,8mOhm,SHLD,G,SMD | PULSE ELECTRONICS (SINGAPORE) | PA4341.821NLT |  | G |  |  |  |  |  |  |  |
|  |  |  |  |  | 198 | 63032RP05-129-G |  | IND,820nH@100KHz,+/-20%,13A,8mOhm,SHLD,G,SMD | MAG.LAYERS, SCIENTIFIC-TECHNICS (KUNSHAN) CO., LTD. | SPS-06CZ-R82M-V1 |  | G |  |  |  |  |  |  |  |
| Multi | ND | ND | Y(4) | 199 | 199 | 610114200-017-G |  | RES,10.7KOhm,+/-1%,1/16W,G,SMD0402 | KOA SPEER ELECTRONICS, INC. | RK73H1ETTP1072F | 8 | G | PUAR2,PSAR2,PRAR2,PQAR2,PPAR2,PIAR2,PFAR2,PEAR2 |  |  |  |  |  |  |
|  |  |  |  |  | 199 | 610114200-024-G |  | RES,10.7KOhm,+/-1%,1/16W,G,SMD0402 | PANASONIC INDUSTRIAL CO.,LTD. | ERJ2RKF1072X |  | G |  |  |  |  |  |  |  |
|  |  |  |  |  | 199 | 610114200-029-G |  | RES,10.7KOhm,+/-1%,1/16W,G,SMD0402 | VISHAY ENTER TECHNO LOGY.INC | CRCW040210K7FKED |  | G |  |  |  |  |  |  |  |
| Multi | N |  | Y(2) | 200 | 200 | 611004D00-017-G |  | RES,1.5KOhm,+/-0.1%,1/16W,G,SMD0402 | KOA SPEER ELECTRONICS, INC. | RN731ETTP1501B25 | 16 | G | PUAR4,PSAR4,PRAR4,PQAR4,PPAR4,PIAR4,PFAR4,PEAR4,PUAR6,PSAR6,PRAR6,PQAR6,PPAR6,PIAR6,PFAR6,PEAR6 |  |  |  |  |  |  |
|  |  |  |  |  | 200 | 611004D00-029-G |  | RES,1.5KOhm,+/-0.1%,1/16W,G,SMD0402 | VISHAY ENTER TECHNO LOGY.INC | TNPW04021K50BEED |  | G |  |  |  |  |  |  |  |
| Multi | N | Other | N | 201 | 201 | 61011JY00-017-G |  | RES,39.2KOhm,+/-1%,1/16W,G,SMD0402 | KOA SPEER ELECTRONICS, INC. | RK73H1ETTP3922F | 11 | G | PUAR5,PSIR5,PSAR5,PRAR5,PQAR5,PPAR5,PIAR5,PFAR5,PETR5,PERR5,PEAR5 |  |  |  |  |  |  |
|  |  |  |  |  | 201 | 61011JY00-029-G |  | RES,39.2KOhm,+/-1%,1/16W,G,SMD0402 | VISHAY ENTER TECHNO LOGY.INC | CRCW040239K2FKED |  | G |  |  |  |  |  |  |  |
| Multi | ND | ND | Y(4) | 202 | 202 | 610117F00-017-G |  | RES,5.76KOhm,+/-1%,1/16W,G,SMD0402 | KOA SPEER ELECTRONICS, INC. | RK73H1ETTP5761F | 16 | G | PUAR8,PSAR8,PRAR8,PQAR8,PPAR8,PIAR8,PFAR8,PEAR8,PUAR11,PSAR11,PRAR11,PQAR11,PPAR11,PIAR11,PFAR11,PEAR11 |  |  |  |  |  |  |
|  |  |  |  |  | 202 | 610117F00-011-G |  | RES,5.76KOhm,+/-1%,1/16W,G,SMD0402 | YAGEO CORPORATION COMPONENT | RC0402FR-075K76L |  | G |  |  |  |  |  |  |  |
|  |  |  |  |  | 202 | 610117F00-044-G |  | RES,5.76KOhm,+/-1%,1/16W,G,SMD0402 | TA-I TECHNOLOGY CO., LTD. | RM04FTN5761 |  | G |  |  |  |  |  |  |  |
| Multi | N | ND | Y(4) | 203 | 203 | 610128200-017-G |  | RES,26.1 Ohm,+/-1%,1/16W,G,SMD0402 | KOA SPEER ELECTRONICS, INC. | RK73H1ETTP26R1F | 8 | G | PUAR10,PSAR10,PRAR10,PQAR10,PPAR10,PIAR10,PFAR10,PEAR10 |  |  |  |  |  |  |
|  |  |  |  |  | 203 | 610128200-029-G |  | RES,26.1 Ohm,+/-1%,1/16W,G,SMD0402 | VISHAY ENTER TECHNO LOGY.INC | CRCW040226R1FKED |  | G |  |  |  |  |  |  |  |
| Sole | Y |  | N | 204 | 204 | 32012NN00-238-G |  | IC,Regulator,IR3898MTRPBF,6A,1.5MHZ,G,QFN-17,SMD | INTERNATIONAL RECTIFIER | IR3898MTRPBF | 11 | G | PUAU1,PSIU1,PSAU1,PRAU1,PQAU1,PPAU1,PIAU1,PFAU1,PETU1,PERU1,PEAU1 |  |  |  |  |  |  |
| Multi | N |  | Y(1) | 205 | 205 | 62012T300-015-G |  | CAP,1uF,+/-10%,X7S,25V,G,SMD0402 | MURATA ELEC. NORTH AMERICA | GRM155C71E105KE11D | 14 | G | PSTC4,PSLC4,PSFC4,PSEC4,PSDC4,PQPC4,PFRC4,PEEC4,PEDC4,PSPC3003,PIPC3003,PFPC3003,PEPC3003,PSRC3010 |  |  |  |  |  |  |
|  |  |  |  |  | 205 | 620138700-026-G |  | CAP,1uF,+/-10%,X6S,25V,G,SMD0402 | SAMSUNG SEMICONDUCTOR | CL05X105KA5NQNC |  | G |  |  |  |  |  |  |  |
|  |  |  |  |  | 205 | 620138700-015-G |  | CAP,1uF,+/-10%,X6S,25V,G,SMD0402 | MURATA ELEC. NORTH AMERICA | GRM155C81E105KE11D |  | G |  |  |  |  |  |  |  |
| Multi | N |  | Y(3) | 206 | 206 | 62012CM01-015-G |  | CAP,10uF,+/-20%,X6S,4V,G,SMD0603 | MURATA ELEC. NORTH AMERICA | GRM188C80G106M | 6 | G | PSLC16,PSFC16,PSEC16,PSDC16,PEEC16,PEDC16 |  |  |  |  |  |  |
|  |  |  |  |  | 206 | 62012CM00-026-G |  | CAP,10uF,+/-20%,X6S,4V,G,SMD0603 | SAMSUNG SEMICONDUCTOR | CL10X106MR8NNNC |  | G |  |  |  |  |  |  |  |
|  |  |  |  |  | 206 | 62012CM00-023-G |  | CAP,10uF,+/-20%,X6S,4V,G,SMD0603 | TAIYO ELECTRIC IND.CO.LTD | AMK107AC6106MA-T |  | G |  |  |  |  |  |  |  |
| Multi | ND | ND | N | 207 | 207 | 63032CD00-088-G |  | IND,2.2uH@100KHz,+/-20%,8A,20mOhm,SHLD,G,SMD | COOPER BUSSMANN, INC. | HCM0703-2R2-R | 5 | G | PETL1,PERL1,PSFL2,PEEL2,PEDL2 |  |  |  |  |  |  |
|  |  |  |  |  | 207 | 630365J00-034-G |  | IND,2.2uH@100KHz,+/-20%,9A,12.8mOhm,SHLD,G,SMD | CYNTEC CO. LTD | CMLE063T-2R2MS |  | G |  |  |  |  |  |  |  |
| Multi | ND | ND | Y(4) | 208 | 208 | 61011HA00-017-G |  | RES,1 Ohm,+/-1%,1/16W,G,SMD0402 | KOA SPEER ELECTRONICS, INC. | RK73H1ETTP1R00F | 13 | G | PSPR4,PIPR4,PFPR4,PEPR4,PSTR5,PSLR5,PSFR5,PSER5,PSDR5,PQPR5,PFRR5,PEER5,PEDR5 |  |  |  |  |  |  |
|  |  |  |  |  | 208 | 61011HA00-029-G |  | RES,1 Ohm,+/-1%,1/16W,G,SMD0402 | VISHAY ENTER TECHNO LOGY.INC | CRCW04021R00FNED |  | G |  |  |  |  |  |  |  |
| Multi | N |  | N | 209 | 209 | 611004M00-017-G |  | RES,16.5KOhm,+/-0.1%,1/16W,G,SMD0402 | KOA SPEER ELECTRONICS, INC. | RN731ETTP1652B25 | 9 | G | PSLR17,PSFR17,PSER17,PSDR17,PQPR17,PFRR17,PEER17,PEDR17,PEDR19 |  |  |  |  |  |  |
|  |  |  |  |  | 209 | 611004M00-024-G |  | RES,16.5KOhm,+/-0.1%,1/16W,G,SMD0402 | PANASONIC INDUSTRIAL CO.,LTD. | ERA2AEB1652X |  | G |  |  |  |  |  |  |  |
| Sole | ND |  | ND | 210 | 210 | 32013PD00-238-G |  | IC,Regulator,IR3883MTRPbF,ADJ,3A,G,QFN-16,SMD | INTERNATIONAL RECTIFIER | IR3883MTRPBF | 9 | G | PSTU1,PSLU1,PSFU1,PSEU1,PSDU1,PQPU1,PFRU1,PEEU1,PEDU1 |  |  |  |  |  |  |
| Multi | ND | ND | Y(5) | 211 | 211 | 611003400-017-G |  | RES,12.7KOhm,+/-0.1%,1/16W,G,SMD0402 | KOA SPEER ELECTRONICS, INC. | RN731ETTP1272B25 | 1 | G | PEER19 |  |  |  |  |  |  |
|  |  |  |  |  | 211 | 611003400-024-G |  | RES,12.7KOhm,+/-0.1%,1/16W,G,SMD0402 | PANASONIC INDUSTRIAL CO.,LTD. | ERA2AEB1272X |  | G |  |  |  |  |  |  |  |
|  |  |  |  |  | 211 | 611003400-029-G |  | RES,12.7KOhm,+/-0.1%,1/16W,G,SMD0402 | VISHAY ENTER TECHNO LOGY.INC | TNPW040212K7BEED |  | G |  |  |  |  |  |  |  |
| Multi | N |  | N | 212 | 212 | 62120HJ00-022-G |  | ECAP,SPEA,270uF,+/-20%,16V,105C,G,SMD6.3X9.9,ESR<=8mOhm | SANYO ELECTRIC CO., LTD. | 16SVPG270M | 5 | G | PSPCE1,PIPCE1,PFPCE1,PEPCE1,PSUCE4 |  |  |  |  |  |  |
|  |  |  |  |  | 212 | 62120LS00-021-G |  | ECAP,Solid Polymer Electrolytic Aluminium Capacitor (SPEA),Low ESR(LESR),270uF,+/-20%,16V,105_x0003_,10mOhm,SMD,6.3*7.7,G | NIPPON CHEMI-CON CORPORATION | APXJ160ARA271MF80J |  | G |  |  |  |  |  |  |  |
| Sole | N | Other | Y(1) | 213 | 213 | 62120CM00-024-G |  | SPEA CAP,220uF,+10%~-35%,6.3V,105C,G,SMD2816,ESR<=15mOhm | PANASONIC INDUSTRIAL CO.,LTD. | EEFCX0J221YR | 14 | G | PSRCE3000,PSRCE3001,PSPCE3003,PIPCE3003,PFPCE3003,PEPCE3003,PSPCE3004,PIPCE3004,PFPCE3004,PEPCE3004,PSPCE3005,PIPCE3005,PFPCE3005,PEPCE3005 |  |  |  |  |  |  |
| Multi | Y | 2 | Y(3) | 214 | 214 | 62010FF00-015-G |  | CAP,47pF,+/-5%,NPO(C0G),50V,G,SMD0402 | MURATA ELEC. NORTH AMERICA | GRM1555C1H470J | 4 | G | PSPC11,PIPC11,PFPC11,PEPC11 |  |  |  |  |  |  |
|  |  |  |  |  | 214 | 62010FF00-026-G |  | CAP,47pF,+/-5%,NPO(C0G),50V,G,SMD0402 | SAMSUNG SEMICONDUCTOR | CL05C470JB5NNNC |  | G |  |  |  |  |  |  |  |
|  |  |  |  |  | 214 | 62010FF00-023-G |  | CAP,47pF,+/-5%,NPO(C0G),50V,G,SMD0402 | TAIYO ELECTRIC IND.CO.LTD | UMK105CG470JV-F |  | G |  |  |  |  |  |  |  |
| Multi | N |  | N | 215 | 215 | 63032CC00-088-G |  | IND,1uH@100KHz,+/-20%,11A,10mOhm,SHLD,G,SMD | COOPER BUSSMANN, INC. | HCM0703-1R0-R | 4 | G | PSPL1,PIPL1,PFPL1,PEPL1 |  |  |  |  |  |  |
|  |  |  |  |  | 215 | 63035CF00-034-G |  | Coil Ind,Shielded(SHLD),1uH@100KHz,+/-20%,10A,10mOhm,SMD,6.95*6.6*2.8,,,G | CYNTEC CO. LTD | CMMS063T1R0MS |  | G |  |  |  |  |  |  |  |
|  |  |  |  |  | 215 | 630362F00-051-G |  | IND,22nH@100KHz,+/-20%,19A,368uOhm,SHLD,G,SMD | PULSE ELECTRONICS (SINGAPORE) | PA4341.102NLT |  | G |  |  |  |  |  |  |  |
| Multi | ND |  | N | 216 | 216 | 630341400-088-G |  | IND,22nH@1MHz,+/-20%,19A,368uOhm,SHLD,G,SMD | COOPER BUSSMANN, INC. | FP0404R1-R022-R | 4 | G | PSPL2,PIPL2,PFPL2,PEPL2 |  |  |  |  |  |  |
|  |  |  |  |  | 216 | 630362G00-065-G |  | IND,22nH@100KHz,+/-20%,19A,0.32mOhm,SHLD,G,SMD | DELTA ELECTRONICS INDUSTRIAL CO.,LTD | HCB0430-220 |  | G |  |  |  |  |  |  |  |
| Multi | ND | ND | Y(4) | 217 | 217 | 61011H300-017-G |  | RES,316 Ohm,+/-1%,1/16W,G,SMD0402 | KOA SPEER ELECTRONICS, INC. | RK73H1ETTP3160F | 4 | G | PSPR5,PIPR5,PFPR5,PEPR5 |  |  |  |  |  |  |
|  |  |  |  |  | 217 | 61011H300-029-G |  | RES,316 Ohm,+/-1%,1/16W,G,SMD0402 | VISHAY ENTER TECHNO LOGY.INC | CRCW0402316RFKEDC |  | G |  |  |  |  |  |  |  |
| Multi | ND | ND | Y(4) | 218 | 218 | 610116R00-017-G |  | RES,14.3KOhm,+/-1%,1/16W,G,SMD0402 | KOA SPEER ELECTRONICS, INC. | RK73H1ETTP1432F | 7 | G | PSPR9,PIPR9,PFPR9,PEPR9,R1074,R1083,R1777 |  |  |  |  |  |  |
|  |  |  |  |  | 218 | 610116R00-029-G |  | RES,thick film,14.3KOhm,+/-1%,1/16W,SMD0402,G | VISHAY ENTER TECHNO LOGY.INC | CRCW040214K3FKED |  | G |  |  |  |  |  |  |  |
| Multi | N |  | Y(5) | 219 | 219 | 61100QQ00-017-G |  | RES,9.76KOhm,+/-0.1%,1/16W,G,SMD0402 | KOA SPEER ELECTRONICS, INC. | RN731ETTP9761B25 | 4 | G | PSPR10,PIPR10,PFPR10,PEPR10 |  |  |  |  |  |  |
|  |  |  |  |  | 219 | 61100QQ00-024-G |  | RES,9.76KOhm,+/-0.1%,1/16W,G,SMD0402 | PANASONIC INDUSTRIAL CO.,LTD. | ERA2AEB9761X |  | G |  |  |  |  |  |  |  |
|  |  |  |  |  | 219 | 61100QQ00-029-G |  | RES,9.76KOhm,+/-0.1%,1/16W,G,SMD0402 | VISHAY ENTER TECHNO LOGY.INC | TNPW04029K76BEED |  | G |  |  |  |  |  |  |  |
| Multi | N | ND | Y(4) | 220 | 220 | 610112J00-017-G |  | RES,200 Ohm,+/-1%,1/16W,G,SMD0402 | KOA SPEER ELECTRONICS, INC. | RK73H1ETTP2000F | 10 | G | PSPR11,PIPR11,PFPR11,PEPR11,R755,R756,R758,R759,R1487,R1541 |  |  |  |  |  |  |
|  |  |  |  |  | 220 | 610112J00-029-G |  | RES,200 Ohm,+/-1%,1/16W,G,SMD0402 | VISHAY ENTER TECHNO LOGY.INC | CRCW0402200RFKED |  | G |  |  |  |  |  |  |  |
|  |  |  |  |  | 220 | 610112J00-024-G |  | RES,200 Ohm,+/-1%,1/16W,G,SMD0402 | PANASONIC INDUSTRIAL CO.,LTD. | ERJ2RKF2000X |  | G |  |  |  |  |  |  |  |
| Multi | N | Other | Y(4) | 221 | 221 | 61011MU00-017-G |  | RES,48.7KOhm,+/-1%,1/16W,G,SMD0402 | KOA SPEER ELECTRONICS, INC. | RK73H1ETTP4872F | 5 | G | PSRR7,PSPR15,PIPR15,PFPR15,PEPR15 |  |  |  |  |  |  |
|  |  |  |  |  | 221 | 61011MU00-029-G |  | RES,48.7KOhm,+/-1%,1/16W,G,SMD0402 | VISHAY ENTER TECHNO LOGY.INC | CRCW040248K7FKED |  | G |  |  |  |  |  |  |  |
| Sole | ND |  | N | 222 | 222 | 32013HH00-238-G |  | IC,Regulator,IR3447MTRPBF,ADJ,25A,G,PQFN-33 | INTERNATIONAL RECTIFIER | IR3447MTRPBF | 4 | G | PSPU1,PIPU1,PFPU1,PEPU1 |  |  |  |  |  |  |
| Multi | N |  | N | 223 | 223 | 62011M802-015-G |  | CAP,62pF,+/-5%,NPO(C0G),50V,G,SMD0402 | MURATA ELEC. NORTH AMERICA | GRM1555C1H620JA01D | 2 | G | PSRC3,PERC3 |  |  |  |  |  |  |
|  |  |  |  |  | 223 | 62011M800-026-G |  | CAP,MLCC,62pF,+/-5%,NPO(C0G),50V,SMD0402,G | SAMSUNG SEMICONDUCTOR | CL05C620JB5NNNC |  | G |  |  |  |  |  |  |  |
| Sole | N |  | N | 224 | 224 | 62013BP00-015-G |  | CAP,22uF,+/-20%,X6S,25V,G,SMD1206 | MURATA ELEC. NORTH AMERICA | GRM31CC81E226ME11L | 10 | G | PSIC4,PETC4,PERC4,PSIC5,PETC5,PERC5,PSIC6,PETC6,PERC6,PETC22 |  |  |  |  |  |  |
| Multi | N |  | N | 225 | 225 | 62013BN00-015-G |  | CAP,4.3nF,+/-10%,X7R,50V,G,SMD0402 | MURATA ELEC. NORTH AMERICA | GRM155R71H432KA01D | 1 | G | PERC7 |  |  |  |  |  |  |
|  |  |  |  |  | 225 | 62010LJ00-023-G |  | CAP,4.7nF,+/-10%,X7R,50V,G,SMD0402 | TAIYO ELECTRIC IND.CO.LTD | UMK105B7472KV-F |  | G |  |  |  |  |  |  |  |
| Multi | N |  | Y(1) | 226 | 226 | 62012PT00-015-G |  | CAP,22uF,+/-20%,X6S,16V,G,SMD0805 | MURATA ELEC. NORTH AMERICA | GRM21BC81C226M | 35 | G | PSTC7,PQPC7,PFRC7,PSTC8,PQPC8,PFRC8,PSRC10,PSTC11,PSRC11,PQPC11,PFRC11,PETC11,PERC11,PSTC12,PSRC12,PQPC12,PFRC12,PETC12,PERC12,PSRC13,PETC13,PERC13,PETC14,PERC14,PSTC15,PQPC15,PFRC15,PETC15,PERC15,PETC16,PERC16,PSRC3012,PSRC3013,PSRC3014,PSRC3015 |  |  |  |  |  |  |
|  |  |  |  |  | 226 | 62012PT00-023-G |  | CAP,22uF,+/-20%,X6S,16V,G,SMD0805 | TAIYO ELECTRIC IND.CO.LTD | EDK212BC6226MG-T |  | G |  |  |  |  |  |  |  |
| Multi | ND | ND | Y(4) | 227 | 227 | 61011PE00-017-G |  | RES,8.87KOhm,+/-1%,1/16W,G,SMD0402 | KOA SPEER ELECTRONICS, INC. | RK73H1ETTP8871F | 1 | G | PERR2 |  |  |  |  |  |  |
|  |  |  |  |  | 227 | 61011PE00-024-G |  | RES,8.87KOhm,+/-1%,1/16W,G,SMD0402 | PANASONIC INDUSTRIAL CO.,LTD. | ERJ2RKF8871X |  | G |  |  |  |  |  |  |  |
|  |  |  |  |  | 227 | 61011PE00-029-G |  | RES,8.87KOhm,+/-1%,1/16W,G,SMD0402 | VISHAY ENTER TECHNO LOGY.INC | CRCW04028K87FKEDC |  | G |  |  |  |  |  |  |  |
| Multi | N |  | Y(5) | 228 | 228 | 61100JA00-017-G |  | RES,8.66KOhm,+/-0.1%,1/16W,G,SMD0402 | KOA SPEER ELECTRONICS, INC. | RN731ETTP8661B25 | 2 | G | PERR8,PERR11 |  |  |  |  |  |  |
|  |  |  |  |  | 228 | 61100JA00-024-G |  | RES,8.66KOhm,+/-0.1%,1/16W,G,SMD0402 | PANASONIC INDUSTRIAL CO.,LTD. | ERA2AEB8661X |  | G |  |  |  |  |  |  |  |
|  |  |  |  |  | 228 | 61100JA00-029-G |  | RES,8.66KOhm,+/-0.1%,1/16W,G,SMD0402 | VISHAY ENTER TECHNO LOGY.INC | TNPW04028K66BEED |  | G |  |  |  |  |  |  |  |
| Multi | N |  | Y(4) | 229 | 229 | 61015JF00-017-G |  | RES,63.4 Ohm,+/-1%,1/10W,G,SMD0402 | KOA SPEER ELECTRONICS, INC. | RK73H1ETTP63R4F | 4 | G | PSIR10,PETR10,PERR10,R938 |  |  |  |  |  |  |
|  |  |  |  |  | 229 | 610129600-011-G |  | RES,63.4 Ohm,+/-1%,1/10W,G,SMD0402 | YAGEO CORPORATION COMPONENT | RC0402FR-0763R4L |  | G |  |  |  |  |  |  |  |
|  |  |  |  |  | 229 | 61015JF00-044-G |  | RES,63.4 Ohm,+/-1%,1/10W,G,SMD0402 | TA-I TECHNOLOGY CO., LTD. | RMH04FT63R4 |  | G |  |  |  |  |  |  |  |
| Multi | N |  | Y(5) | 230 | 230 | 61100PW00-017-G |  | RES,1.54KOhm,+/-0.1%,1/16W,G,SMD0402 | KOA SPEER ELECTRONICS, INC. | RN731ETTP1541B25 | 2 | G | PERR13,PERR15 |  |  |  |  |  |  |
|  |  |  |  |  | 230 | 61100PW00-024-G |  | RES,1.54KOhm,+/-0.1%,1/16W,G,SMD0402 | PANASONIC INDUSTRIAL CO.,LTD. | ERA2AEB1541X |  | G |  |  |  |  |  |  |  |
|  |  |  |  |  | 230 | 61100PW00-029-G |  | RES,1.54KOhm,+/-0.1%,1/16W,G,SMD0402 | VISHAY ENTER TECHNO LOGY.INC | TNPW04021K54BEED |  | G |  |  |  |  |  |  |  |
| Sole | N |  | N | 231 | 231 | 62011LT01-015-G |  | CAP,130pF,+/-5%,NPO(C0G),50V,G,SMD0402 | MURATA ELEC. NORTH AMERICA | GRM1555C1H131JA01D | 1 | G | PETC3 |  |  |  |  |  |  |
| Multi | ND | ND | Y(3) | 232 | 232 | 62011AM00-015-G |  | CAP,6.8nF,+/-10%,X7R,50V,G,SMD0402 | MURATA ELEC. NORTH AMERICA | GRM155R71H682K | 1 | G | PETC7 |  |  |  |  |  |  |
|  |  |  |  |  | 232 | 62011AM00-023-G |  | CAP,6.8nF,+/-10%,X7R,50V,G,SMD0402 | TAIYO ELECTRIC IND.CO.LTD | UMK105B7682KV-F |  | G |  |  |  |  |  |  |  |
|  |  |  |  |  | 232 | 62011AM00-026-G |  | CAP,6.8nF,+/-10%,X7R,50V,G,SMD0402 | SAMSUNG SEMICONDUCTOR | CL05B682KB5NNNC |  | G |  |  |  |  |  |  |  |
| Multi | N | ND | Y(4) | 233 | 233 | 61011KY00-017-G |  | RES,3.83KOhm,+/-1%,1/16W,G,SMD0402 | KOA SPEER ELECTRONICS, INC. | RK73H1ETTP3831F | 1 | G | PETR2 |  |  |  |  |  |  |
|  |  |  |  |  | 233 | 61011KY00-029-G |  | RES,3.83KOhm,+/-1%,1/16W,G,SMD0402 | VISHAY ENTER TECHNO LOGY.INC | CRCW04023K83FKED |  | G |  |  |  |  |  |  |  |
| Multi | N |  | Y(5) | 234 | 234 | 611007000-017-G |  | RES,8.25KOhm,+/-0.1%,1/16W,G,SMD0402 | KOA SPEER ELECTRONICS, INC. | RN731ETTP8251B25 | 4 | G | PSIR8,PETR8,PSIR11,PETR11 |  |  |  |  |  |  |
|  |  |  |  |  | 234 | 611007000-011-G |  | RES,8.25KOhm,+/-0.1%,1/16W,G,SMD0402 | YAGEO CORPORATION COMPONENT | RT0402BRD078K25L |  | G |  |  |  |  |  |  |  |
| Multi | ND | ND | Y(5) | 235 | 235 | 61100AW00-017-G |  | RES,909 Ohm,+/-0.1%,1/16W,G,SMD0402 | KOA SPEER ELECTRONICS, INC. | RN731ETTP9090B25 | 2 | G | PETR13,PETR15 |  |  |  |  |  |  |
|  |  |  |  |  | 235 | 61100AW00-024-G |  | RES,909 Ohm,+/-0.1%,1/16W,G,SMD0402 | PANASONIC INDUSTRIAL CO.,LTD. | ERA2AEB9090X |  | G |  |  |  |  |  |  |  |
|  |  |  |  |  | 235 | 61100AW00-029-G |  | RES,909 Ohm,+/-0.1%,1/16W,G,SMD0402 | VISHAY ENTER TECHNO LOGY.INC | TNPW0402909RBEED |  | G |  |  |  |  |  |  |  |
| Multi | Y | 2 | Y(3) | 236 | 236 | 620105U00-015-G |  | CAP,220pF,+/-10%,X7R,50V,G,SMD0402 | MURATA ELEC. NORTH AMERICA | GRM155R71H221K | 3 | G | PSTC14,PQPC14,PFRC14 |  |  |  |  |  |  |
|  |  |  |  |  | 236 | 620105U00-023-G |  | CAP,220pF,+/-10%,X7R,50V,G,SMD0402 | TAIYO ELECTRIC IND.CO.LTD | UMK105B7221KV-F |  | G |  |  |  |  |  |  |  |
|  |  |  |  |  | 236 | 620105U00-026-G |  | CAP,220pF,+/-10%,X7R,50V,G,SMD0402 | SAMSUNG SEMICONDUCTOR | CL05B221KB5NNNC |  | G |  |  |  |  |  |  |  |
| Multi | N |  | N | 237 | 237 | 63032PP00-088-G |  | IND,4.7uH@100KHz,+/-20%,5.5A,40mOhm,SHLD,G,SMD | COOPER BUSSMANN, INC. | HCM0703-4R7-R | 2 | G | PQPL2,PFRL2 |  |  |  |  |  |  |
|  |  |  |  |  | 237 | 63030PW00-034-G |  | Coil Ind,Shielded(SHLD),4.7uH@100KHz,+/-20%,5.5A,40mOhm,SMD,7.3*6.6*3.0,G | CYNTEC CO. LTD | PCMC063T-4R7MN |  | G |  |  |  |  |  |  |  |
|  |  |  |  |  | 237 | 63031AD04-129-G |  | IND,4.7uH@100KHz,+/-20%,5.5A,40mOhm,SHLD,G,SMD | MAG.LAYERS, SCIENTIFIC-TECHNICS (KUNSHAN) CO., LTD. | SPS-06CZ-4R7M-V1 |  | G |  |  |  |  |  |  |  |
| Multi | ND | ND | Y(4) | 238 | 238 | 61011R400-017-G |  | RES,34.8KOhm,+/-1%,1/16W,G,SMD0402 | KOA SPEER ELECTRONICS, INC. | RK73H1ETTP3482F | 1 | G | PFRR1 |  |  |  |  |  |  |
|  |  |  |  |  | 238 | 61011R400-024-G |  | RES,34.8KOhm,+/-1%,1/16W,G,SMD0402 | PANASONIC INDUSTRIAL CO.,LTD. | ERJ2RKF3482X |  | G |  |  |  |  |  |  |  |
| Multi | N |  | N | 239 | 239 | 61100YB00-017-G |  | RES,2.94KOhm,+/-0.1%,1/16W,G,SMD0402 | KOA SPEER ELECTRONICS, INC. | RN731ETTP2941B25 | 1 | G | PFRR19 |  |  |  |  |  |  |
|  |  |  |  |  | 239 | 61100YB00-011-G |  | RES,2.94KOhm,+/-0.1%,1/16W,SMD0402,G | YAGEO CORPORATION COMPONENT | RT0402BRD072K94L |  | G |  |  |  |  |  |  |  |
|  |  |  |  |  | 239 | 61100YB00-044-G |  | RES,2.94KOhm,+/-0.1%,1/16W,G,SMD0402 | TA-I TECHNOLOGY CO., LTD. | RB04BTP2941 |  | G |  |  |  |  |  |  |  |
| Multi | ND | ND | Y(3) | 240 | 240 | 62011DB01-015-G |  | CAP,1nF,+/-10%,X7R,100V,G,SMD0402 | MURATA ELEC. NORTH AMERICA | GRM155R72A102KA01D | 1 | G | PHAC3 |  |  |  |  |  |  |
|  |  |  |  |  | 240 | 62011DB00-011-G |  | CAP,1nF,+/-10%,X7R,100V,G,SMD0402 | YAGEO CORPORATION COMPONENT | CC0402KRX7R0BB102 |  | G |  |  |  |  |  |  |  |
| Sole | ND |  | Y(1) | 241 | 241 | 620135500-015-G |  | CAP,39nF,+/-10%,X7R,100V,G,SMD0805 | MURATA ELEC. NORTH AMERICA | GRM21BR72A393KA01L | 1 | G | PHAC18 |  |  |  |  |  |  |
| Multi | ND |  | ND | 242 | 242 | 52170KE00-086-G |  | TVS Diode,SMCJ64A,G,DO-214AB-2,SMD | LITTELFUSE FAR EAST PTE LTD | SMCJ64A | 1 | G | PHAD1 |  |  |  |  |  |  |
|  |  |  |  |  | 242 | 52170ER00-237-G |  | TVS Diode,SMCJ64A-13-F,SMC/DO-214AB,2P,G | DIODES INCORPORATION | SMCJ64A-13-F |  | G |  |  |  |  |  |  |  |
| Sole | N |  | N | 243 | 243 | 52030YE00-223-G |  | DIODE,Schottky,MBR5H100MFST1G,100V,5A,G,SO8FL-8,SMD | ON SEMICONDUCTOR CORP | MBR5H100MFST1G | 1 | G | PHAD2 |  |  |  |  |  |  |
| Multi | Y | ND | N | 244 | 244 | 52040EC00-237-G |  | DIODE,Zener,MMSZ5246B-7-F,16V,7.8mA,G,SOD123-2,SMD | DIODES INEORPORATION | MMSZ5246B-7-F | 1 | G | PHAD3 |  |  |  |  |  |  |
|  |  |  |  |  | 244 | 52040B500-223-G |  | DIODE,Zener,MMSZ5246BT1G,16V,7.8mA,G,SOD123-2,SMD | ON SEMICONDUCTOR CORP | MMSZ5246BT1G |  | G |  |  |  |  |  |  |  |
|  |  |  |  |  | 244 | 52040EY00-031-G |  | Diode,ZENER,BZT52H-C16,17.1V,5mA,G,SOD123F-2,SMD | NXP SEMICONDUCTORS | BZT52H-C16 |  | G |  |  |  |  |  |  |  |
| Multi | N |  | N | 245 | 245 | 51031VY00-031-G |  | MOS N,PSMN4R8-100BSE,100V,120A,4.8m@10V,G,SOT404-3,SMD | NXP SEMICONDUCTORS | PSMN4R8-100BSE | 3 | G | PHAQ1,PHAQ2,PHAQ3 |  |  |  |  |  |  |
|  |  |  |  |  | 245 | 51032HE00-185-G |  | MOS N,FDB047N10,100V,120A,3.9m@10V,G,TO263-3,SMD | FAIRCHILD SEMICONDUCTOR CORP | FDB047N10 |  | G |  |  |  |  |  |  |  |
|  |  |  |  |  | 245 | 51032JY00-029-G |  | MOS N,SUM70040E-GE3,100V,120A,G,TO-263-3,SMD | VISHAY ENTER TECHNO LOGY.INC | SUM70040E-GE3 |  | G |  |  |  |  |  |  |  |
| Multi | ND |  | N | 246 | 246 | 51020A000-031-G |  | TRANS P,PBHV9115T,150V,1A,G,SOT23-3,SMD | NXP SEMICONDUCTORS | PBHV9115T | 1 | G | PHAQ4 |  |  |  |  |  |  |
|  |  |  |  |  | 246 | 51020BJ00-185-G |  | Trans PNP,MMBT5401,-150V,-600mA,G,SOT-23-3,SMD | FAIRCHILD SEMICONDUCTOR CORP | MMBT5401 |  | G |  |  |  |  |  |  |  |
|  |  |  |  |  | 246 | 510204N00-237-G |  | Trans PNP,MMBT5401-7-F,-150V,-600mA,SOT-23,3P,G | DIODES INCORPORATION | MMBT5401-7-F |  | G |  |  |  |  |  |  |  |
| Single | N |  | N | 247 | 247 | 51032D100-237-G |  | MOS N,DMN10H220L-7,100V,1.6A,220m@10V,G,SOT-23-3,SMD | DIODES INCORPORATION | DMN10H220L-7 | 2 | G | PHAQ5,PHAQ6 |  |  |  |  |  |  |
| Sole | ND |  | ND | 248 | 248 | 610601801-32D-G |  | RES,0.5mOhm,+/-1%,2W,G,SMD1225 | Thin Film Technology Corporation | CPA1225R0M50FW-T5 | 1 | G | PHAR1 |  |  |  |  |  |  |
| Multi | ND |  | Y(5) | 249 | 249 | 61100DA00-017-G |  | RES,33KOhm,+/-0.1%,1/16W,G,SMD0402 | KOA SPEER ELECTRONICS, INC. | RN731ETTP3302B25 | 1 | G | PHAR2 |  |  |  |  |  |  |
|  |  |  |  |  | 249 | 61100DA00-011-G |  | RES,33KOhm,+/-0.1%,1/16W,G,SMD0402 | YAGEO CORPORATION COMPONENT | RT0402BRD0733KL |  | G |  |  |  |  |  |  |  |
| Multi | ND |  | Y(5) | 250 | 250 | 61100QM00-017-G |  | RES,100KOhm,+/-0.1%,1/10W,G,SMD0603 | KOA SPEER ELECTRONICS, INC. | RN73H1JTTD1003B25 | 1 | G | PHAR5 |  |  |  |  |  |  |
|  |  |  |  |  | 250 | 61100QM00-011-G |  | RES,100KOhm,+/-0.1%,1/10W,G,SMD0603 | YAGEO CORPORATION COMPONENT | RT0603BRD07100KL |  | G |  |  |  |  |  |  |  |
| Multi | ND | ND | Y(4) | 251 | 251 | 610100R00-017-G |  | RES,3.74KOhm,+/-1%,1/10W,G,SMD0603 | KOA SPEER ELECTRONICS, INC. | RK73H1JTTD3741F | 1 | G | PHAR6 |  |  |  |  |  |  |
|  |  |  |  |  | 251 | 610100R00-024-G |  | RES,3.74KOhm,+/-1%,1/10W,G,SMD0603 | PANASONIC INDUSTRIAL CO.,LTD. | ERJ3EKF3741V |  | G |  |  |  |  |  |  |  |
|  |  |  |  |  | 251 | 610100R00-029-G |  | RES,3.74KOhm,+/-1%,1/10W,G,SMD0603 | VISHAY ENTER TECHNO LOGY.INC | CRCW06033K74FKEB |  | G |  |  |  |  |  |  |  |
| Multi | N | Other | Y(4) | 252 | 252 | 610107P00-017-G |  | RES,4.12KOhm,+/-1%,1/10W,G,SMD0603 | KOA SPEER ELECTRONICS, INC. | RK73H1JTTD4121F | 1 | G | PHAR7 |  |  |  |  |  |  |
|  |  |  |  |  | 252 | 610107P00-011-G |  | RES,4.12KOhm,+/-1%,1/10W,G,SMD0603 | YAGEO CORPORATION COMPONENT | RC0603FR-074K12L |  | G |  |  |  |  |  |  |  |
|  |  |  |  |  | 252 | 610107P00-044-G |  | RES,4.12KOhm,+/-1%,1/10W,G,SMD0603 | TA-I TECHNOLOGY CO., LTD. | RM06FTN4121 |  | G |  |  |  |  |  |  |  |
| Multi | ND |  | Y(4) | 253 | 253 | 61013GW00-017-G |  | RES,150KOhm,+/-1%,1/8W,G,SMD0805 | KOA SPEER ELECTRONICS, INC. | RK73H2ATTD1503F | 1 | G | PHAR13 |  |  |  |  |  |  |
|  |  |  |  |  | 253 | 61013GW00-011-G |  | RES,150KOhm,+/-1%,1/8W,G,SMD0805 | YAGEO CORPORATION COMPONENT | RC0805FR-07150KL |  | G |  |  |  |  |  |  |  |
|  |  |  |  |  | 253 | 61013GW00-044-G |  | RES,150KOhm,+/-1%,1/8W,G,SMD0805 | TA-I TECHNOLOGY CO., LTD. | RM10FTN1503 |  | G |  |  |  |  |  |  |  |
| Multi | N | ND | Y(4) | 254 | 254 | 610119P00-017-G |  | RES,5.11KOhm,+/-1%,1/16W,G,SMD0402 | KOA SPEER ELECTRONICS, INC. | RK73H1ETTP5111F | 1 | G | PHAR20 |  |  |  |  |  |  |
|  |  |  |  |  | 254 | 610119P00-024-G |  | RES,5.11KOhm,+/-1%,1/16W,G,SMD0402 | PANASONIC INDUSTRIAL CO.,LTD. | ERJ2RKF5111X |  | G |  |  |  |  |  |  |  |
|  |  |  |  |  | 254 | 610119P00-029-G |  | RES,5.11KOhm,+/-1%,1/16W,G,SMD0402 | VISHAY ENTER TECHNO LOGY.INC | CRCW04025K11FKED |  | G |  |  |  |  |  |  |  |
| Single | ND | ND | Y(4) | 255 | 255 | 610113D00-017-G |  | RES,10.5KOhm,+/-1%,1/16W,G,SMD0402 | KOA SPEER ELECTRONICS, INC. | RK73H1ETTP1052F | 1 | G | PHAR35 |  |  |  |  |  |  |
| Multi | ND | ND | Y(4) | 256 | 256 | 61012Y700-017-G |  | RES,49.9KOhm,+/-1%,1/8W,G,SMD0805 | KOA SPEER ELECTRONICS, INC. | RK73H2ATTD4992F | 1 | G | PHAR78 |  |  |  |  |  |  |
|  |  |  |  |  | 256 | 61012Y700-011-G |  | RES,49.9KOhm,+/-1%,1/8W,G,SMD0805 | YAGEO CORPORATION COMPONENT | RC0805FR-0749K9L |  | G |  |  |  |  |  |  |  |
|  |  |  |  |  | 256 | 61012Y700-044-G |  | RES,49.9KOhm,+/-1%,1/8W,G,SMD0805 | TA-I TECHNOLOGY CO., LTD. | RM10FTN4992 |  | G |  |  |  |  |  |  |  |
| Sole | ND |  | Y(1) | 257 | 257 | 32023RR00-183-G |  | IC,Power Controller,LM5066IPMHX/NOPB,G,HTSSOP-28,SMD | TEXAS INSTRUMENTS | LM5066IPMHX/NOPB | 1 | G | PHAU1 |  |  |  |  |  |  |
| Multi | N |  | Y(5) | 258 | 258 | 611006C00-017-G |  | RES,4.12KOhm,+/-0.1%,1/16W,G,SMD0402 | KOA SPEER ELECTRONICS, INC. | RN731ETTP4121B25 | 3 | G | PSIR13,PSIR15,PQPR19 |  |  |  |  |  |  |
|  |  |  |  |  | 258 | 611006C00-024-G |  | RES,4.12KOhm,+/-0.1%,1/16W,G,SMD0402 | PANASONIC INDUSTRIAL CO.,LTD. | ERA2AEB4121X |  | G |  |  |  |  |  |  |  |
|  |  |  |  |  | 258 | 611006C00-029-G |  | RES,4.12KOhm,+/-0.1%,1/16W,G,SMD0402 | VISHAY ENTER TECHNO LOGY.INC | TNPW04024K12BEED |  | G |  |  |  |  |  |  |  |
| Multi | ND |  | N | 259 | 259 | 630328U00-088-G |  | IND,3.3uH@100KHz,+/-20%,6A,30mOhm,SHLD,G,SMD | COOPER BUSSMANN, INC. | HCM0703-3R3-R | 3 | G | PSTL2,PSLL2,PSDL2 |  |  |  |  |  |  |
|  |  |  |  |  | 259 | 63034QP00-034-G |  | IND,3.3uH@100KHz,+/-20%,6.5A,21mOhm,SHLD,G,SMD | CYNTEC CO. LTD | PCME063T-3R3MS |  | G |  |  |  |  |  |  |  |
| Multi | N |  | Y(5) | 260 | 260 | 61100KM01-017-G |  | RES,15KOhm,+/-0.1%,1/16W,G,SMD0402 | KOA SPEER ELECTRONICS, INC. | RN73H1ETTP1502B25 | 1 | G | PSDR19 |  |  |  |  |  |  |
|  |  |  |  |  | 260 | 61100KM02-024-G |  | RES,15KOhm,+/-0.1%,1/16W,G,SMD0402 | PANASONIC INDUSTRIAL CO.,LTD. | ERA2AEB153X |  | G |  |  |  |  |  |  |  |
| Multi | ND |  | N | 261 | 261 | 63032A900-088-G |  | IND,1.5uH@100KHz,+/-20%,9A,15mOhm,SHLD,G,SMD | COOPER BUSSMANN, INC. | HCM0703-1R5-R | 2 | G | PSIL1,PSEL2 |  |  |  |  |  |  |
|  |  |  |  |  | 261 | 63032BW00-034-G |  | IND,1.5uH@100KHz,+/-20%,9A,15mOhm,SHLD,G,SMD | CYNTEC CO. LTD | PCMC063T-1R5MN |  | G |  |  |  |  |  |  |  |
|  |  |  |  |  | 261 | 63030HW00-051-G |  | IND,1.5uH@100KHz,+/-20%,9A,11.8mOhm,SHLD,G,SMD | PULSE ELECTRONICS (SINGAPORE) | PG0426.152NLT |  | G |  |  |  |  |  |  |  |
| Multi | ND |  | Y(5) | 262 | 262 | 61100V400-017-G |  | RES,13.7KOhm,+/-0.1%,1/16W,G,SMD0402 | KOA SPEER ELECTRONICS, INC. | RN731ETTP1372B25 | 1 | G | PSER19 |  |  |  |  |  |  |
|  |  |  |  |  | 262 | 61100V400-024-G |  | RES,13.7KOhm,+/-0.1%,1/16W,G,SMD0402 | PANASONIC INDUSTRIAL CO.,LTD. | ERA2AEB1372X |  | G |  |  |  |  |  |  |  |
|  |  |  |  |  | 262 | 61100V400-029-G |  | RES,13.7KOhm,+/-0.1%,1/16W,G,SMD0402 | VISHAY ENTER TECHNO LOGY.INC | TNPW040213K7BEED |  | G |  |  |  |  |  |  |  |
| Multi | ND |  | Y | 263 | 263 | 61100Y900-017-G |  | RES,11.8KOhm,+/-0.1%,1/16W,G,SMD0402 | KOA SPEER ELECTRONICS, INC. | RN731ETTP1182B25 | 1 | G | PSFR19 |  |  |  |  |  |  |
|  |  |  |  |  | 263 | 61100Y900-024-G |  | RES,11.8KOhm,+/-0.1%,1/16W,G,SMD0402 | PANASONIC INDUSTRIAL CO.,LTD. | ERA2AEB1182X |  | G |  |  |  |  |  |  |  |
|  |  |  |  |  | 263 | 61100Y900-029-G |  | RES,11.8KOhm,+/-0.1%,1/16W,G,SMD0402 | VISHAY ENTER TECHNO LOGY.INC | TNPW040211K8BEED |  | G |  |  |  |  |  |  |  |
| Sole | N | ND | Y(3) | 264 | 264 | 62011LY01-015-G |  | CAP,160pF,+/-5%,NPO(C0G),50V,G,SMD0402 | MURATA ELEC. NORTH AMERICA | GRM1555C1H161JA01D | 1 | G | PSIC3 |  |  |  |  |  |  |
| Multi | ND | ND | Y(4) | 265 | 265 | 61011MA00-017-G |  | RES,3.32KOhm,+/-1%,1/16W,G,SMD0402 | KOA SPEER ELECTRONICS, INC. | RK73H1ETTP3321F | 1 | G | PSIR2 |  |  |  |  |  |  |
|  |  |  |  |  | 265 | 61011MA00-024-G |  | RES,3.32KOhm,+/-1%,1/16W,G,SMD0402 | PANASONIC INDUSTRIAL CO.,LTD. | ERJ2RKF3321X |  | G |  |  |  |  |  |  |  |
|  |  |  |  |  | 265 | 61011MA00-029-G |  | RES,3.32KOhm,+/-1%,1/16W,G,SMD0402 | VISHAY ENTER TECHNO LOGY.INC | CRCW04023K32FKED |  | G |  |  |  |  |  |  |  |
| Multi | ND |  | Y(5) | 266 | 266 | 61100DF00-017-G |  | RES,6.34KOhm,+/-0.1%,1/16W,G,SMD0402 | KOA SPEER ELECTRONICS, INC. | RN731ETTP6341B25 | 1 | G | PSLR19 |  |  |  |  |  |  |
|  |  |  |  |  | 266 | 61100DF00-024-G |  | RES,6.34KOhm,+/-0.1%,1/16W,G,SMD0402 | PANASONIC INDUSTRIAL CO.,LTD. | ERA2AEB6341X |  | G |  |  |  |  |  |  |  |
|  |  |  |  |  | 266 | 61100DF00-029-G |  | RES,6.34KOhm,+/-0.1%,1/16W,G,SMD0402 | VISHAY ENTER TECHNO LOGY.INC | TNPW04026K34BEED |  | G |  |  |  |  |  |  |  |
| Sole | N |  | N | 267 | 267 | 62013BS00-015-G |  | CAP,3nF,+/-10%,X7R,50V,G,SMD0402 | MURATA ELEC. NORTH AMERICA | GRM155R71H302KA01D | 1 | G | PSPC10 |  |  |  |  |  |  |
| Multi | ND | ND | N | 268 | 268 | 62120BA00-022-G |  | SPEA,CAP,180uF,+/-20%,16V,105C,G,SMD6.3*5.9,ESR<=22mOhm | SANYO ELECTRIC CO., LTD. | 16SVPF180M | 1 | G | PSRCE1 |  |  |  |  |  |  |
|  |  |  |  |  | 268 | 62120D701-021-G |  | SPEA CAP,180uF,+/-20%,16V,105_x0003_,G,SMD6.3*5.8,ESR<=22mOhm | NIPPON CHEMI-CON CORPORATION | APXG160ARA181MF61G |  | G |  |  |  |  |  |  |  |
| Sole | ND |  | Y(1) | 269 | 269 | 62012T500-015-G |  | CAP,22uF,+/-20%,X7S,25V,G,SMD1206 | MURATA ELEC. NORTH AMERICA | GRM31CC71E226ME11L | 12 | G | PSRC4,PSUC5,PSRC5,PSUC6,PSRC6,PSUC7,PSUC8,PSUC9,PSUC10,PSRC3001,PSRC3002,PSRC3005 |  |  |  |  |  |  |
| Sole | N |  | N | 270 | 270 | 62013BQ00-015-G |  | CAP,3.6nF,+/-10%,X7R,50V,G,SMD0402 | MURATA ELEC. NORTH AMERICA | GRM155R71H362KA01D | 1 | G | PSRC7 |  |  |  |  |  |  |
| Multi | ND | ND | N | 271 | 271 | 63033PG00-15A-G |  | IND,22nH@100KHz,+/-15%,22A,249.55uOhm,SHLD,G,SMD | The Inter-Technical Group, Inc. | SLC1615A-R022LHF | 1 | G | PSRL1 |  |  |  |  |  |  |
|  |  |  |  |  | 271 | 63035Y500-129-G |  | IND,22nH@100KHz,+/-15%,22A,249.55uOhm,SHLD,G,SMD | MAG.LAYERS, SCIENTIFIC-TECHNICS (KUNSHAN) CO., LTD. | MSI-400404-22NL-I |  | G |  |  |  |  |  |  |  |
|  |  |  |  |  | 271 | 63035SH00-065-G |  | IND,22nH@100KHz,+/-15%,22A,249.55uOhm,SHLD,G,SMD | DELTA ELECTRONICS INDUSTRIAL CO.,LTD | HCB0439-220 |  | G |  |  |  |  |  |  |  |
| Multi | ND |  | N | 272 | 272 | 63034GW00-088-G |  | IND,680nH@100KHz,+/-20%,34A,1.33mOhm,SHLD,G,SMD | COOPER BUSSMANN, INC. | HCM1305-R68-R | 1 | G | PSRL2 |  |  |  |  |  |  |
|  |  |  |  |  | 272 | 630365H00-034-G |  | IND,680nH@100KHz,+/-20%,29.5A,1.55mOhm,SHLD,G,SMD | CYNTEC CO. LTD | CMLB135T-R68MS |  | G |  |  |  |  |  |  |  |
| Multi | ND | ND | Y(4) | 273 | 273 | 61011MN00-017-G |  | RES,976 Ohm,+/-1%,1/16W,G,SMD0402 | KOA SPEER ELECTRONICS, INC. | RK73H1ETTP9760F | 1 | G | PSRR11 |  |  |  |  |  |  |
|  |  |  |  |  | 273 | 61011MN00-029-G |  | RES,976 Ohm,+/-1%,1/16W,G,SMD0402 | VISHAY ENTER TECHNO LOGY.INC | CRCW0402976RFKED |  | G |  |  |  |  |  |  |  |
| Multi | ND |  | Y(5) | 274 | 274 | 61100P800-017-G |  | RES,8.45KOhm,+/-0.1%,1/16W,G,SMD0402 | KOA SPEER ELECTRONICS, INC. | RN731ETTP8451B25 | 1 | G | PSRR12 |  |  |  |  |  |  |
|  |  |  |  |  | 274 | 61100P800-024-G |  | RES,8.45KOhm,+/-0.1%,1/16W,G,SMD0402 | PANASONIC INDUSTRIAL CO.,LTD. | ERA2AEB8451X |  | G |  |  |  |  |  |  |  |
|  |  |  |  |  | 274 | 61100P800-029-G |  | RES,8.45KOhm,+/-0.1%,1/16W,G,SMD0402 | VISHAY ENTER TECHNO LOGY.INC | TNPW04028K45BEED |  | G |  |  |  |  |  |  |  |
| Multi | N | ND | Y(4) | 275 | 275 | 610114A00-017-G |  | RES,24.9KOhm,+/-1%,1/16W,G,SMD0402 | KOA SPEER ELECTRONICS, INC. | RK73H1ETTP2492F | 1 | G | PSRR13 |  |  |  |  |  |  |
|  |  |  |  |  | 275 | 610114A00-024-G |  | RES,24.9KOhm,+/-1%,1/16W,G,SMD0402 | PANASONIC INDUSTRIAL CO.,LTD. | ERJ2RKF2492X |  | G |  |  |  |  |  |  |  |
|  |  |  |  |  | 275 | 610114A00-029-G |  | RES,24.9KOhm,+/-1%,1/16W,G,SMD0402 | VISHAY ENTER TECHNO LOGY.INC | CRCW040224K9FKED |  | G |  |  |  |  |  |  |  |
| Multi | ND |  | Y(5) | 276 | 276 | 61100PM00-017-G |  | RES,453 Ohm,+/-0.1%,1/16W,G,SMD0402 | KOA SPEER ELECTRONICS, INC. | RN731ETTP4530B25 | 1 | G | PSRR17 |  |  |  |  |  |  |
|  |  |  |  |  | 276 | 61100PM00-011-G |  | RES,453 Ohm,+/-0.1%,1/16W,G,SMD0402 | YAGEO CORPORATION COMPONENT | RT0402BRD07453RL |  | G |  |  |  |  |  |  |  |
|  |  |  |  |  | 276 | 61100PM00-044-G |  | RES,453 Ohm,+/-0.1%,1/16W,G,SMD0402 | TA-I TECHNOLOGY CO., LTD. | RB04BTP4530 |  | G |  |  |  |  |  |  |  |
| Multi | ND |  | Y(4) | 277 | 277 | 61011C300-017-G |  | RES,2.2 Ohm,+/-1%,1/16W,G,SMD0402 | KOA SPEER ELECTRONICS, INC. | RK73H1ETTP2R20F | 1 | G | PSRR3006 |  |  |  |  |  |  |
|  |  |  |  |  | 277 | 61011C300-011-G |  | RES,2.2 Ohm,+/-1%,1/16W,G,SMD0402 | YAGEO CORPORATION COMPONENT | RC0402FR-072R2L |  | G |  |  |  |  |  |  |  |
|  |  |  |  |  | 277 | 61011C300-044-G |  | RES,2.2 Ohm,+/-1%,1/16W,G,SMD0402 | TA-I TECHNOLOGY CO., LTD. | RM04FTN2R20 |  | G |  |  |  |  |  |  |  |
| Sole | ND |  | N | 278 | 278 | 32013FK00-238-G |  | IC,Regulator,IR3846MTRPBF,ADJ,35A,G,PQFN-26,SMD | INTERNATIONAL RECTIFIER | IR3846MTRPBF | 1 | G | PSRU1 |  |  |  |  |  |  |
| Multi | N |  | Y(5) | 279 | 279 | 61100QA00-017-G |  | RES,16KOhm,+/-0.1%,1/16W,G,SMD0402 | KOA SPEER ELECTRONICS, INC. | RN731ETTP1602B25 | 1 | G | PSTR17 |  |  |  |  |  |  |
|  |  |  |  |  | 279 | 61100QA01-024-G |  | RES,16KOhm,+/-0.1%,1/16W,G,SMD0402 | PANASONIC INDUSTRIAL CO.,LTD. | ERA2AEB163X |  | G |  |  |  |  |  |  |  |
|  |  |  |  |  | 279 | 61100QA00-029-G |  | RES,16KOhm,+/-0.1%,1/16W,G,SMD0402 | VISHAY ENTER TECHNO LOGY.INC | TNPW040216K0BEED |  | G |  |  |  |  |  |  |  |
| Multi | N | ND | Y(5) | 280 | 280 | 61100J401-017-G |  | RES,1.78KOhm,+/-0.1%,1/16W,G,SMD0402 | KOA SPEER ELECTRONICS, INC. | RN73H1ETTP1781B25 | 1 | G | PSTR19 |  |  |  |  |  |  |
|  |  |  |  |  | 280 | 61100J400-024-G |  | RES,1.78KOhm,+/-0.1%,1/16W,G,SMD0402 | PANASONIC INDUSTRIAL CO.,LTD. | ERA2AEB1781X |  | G |  |  |  |  |  |  |  |
| Multi | ND | ND | Y(3) | 281 | 281 | 510301N00-223-G |  | MOS N,2N7002LT1G,60V,0.115A,7.5ohm@5V,G,SOT23-3,SMD | ON SEMICONDUCTOR CORP | 2N7002LT1G | 4 | G | PSUQ1,Q2,Q6,Q15 |  |  |  |  |  |  |
|  |  |  |  |  | 281 | 51030CQ00-185-G |  | MOS N,2N7002,60V,115mA,7.5ohm@5V,G,SOT23-3,SMD | FAIRCHILD SEMICONDUCTOR CORP | 2N7002 |  | G |  |  |  |  |  |  |  |
| Single | N |  | Y(4) | 282 | 282 | 610119C00-017-G |  | RES,130KOhm,+/-1%,1/16W,G,SMD0402 | KOA SPEER ELECTRONICS, INC. | RK73H1ETTP1303F | 1 | G | PSUR1 |  |  |  |  |  |  |
| Multi | N |  | N | 283 | 283 | 880302300-065-G |  | Converter,input 40V~60V,600W,G,Q54SJ12050NNDH,OVAL | DELTA ELECTRONICS INDUSTRIAL CO.,LTD | Q54SJ12050NNDH | 1 | G | PSUU1 |  |  |  |  |  |  |
|  |  |  |  |  | 283 | 880302100-065-G |  | Converter,input 40V~60V,600W,G,Q54SH12050NNDH | DELTA ELECTRONICS INDUSTRIAL CO.,LTD | Q54SH12050NNDH |  | G |  |  |  |  |  |  |  |
| Multi | ND | ND | N | 284 | 284 | 510503B00-223-G |  | MOS N/N,NTZD3154NT1G,20V,0.54A,550m24.5V,G,SOT563-6,SMD | ON SEMICONDUCTOR CORP | NTZD3154NT1G | 2 | G | QN2,QN3 |  |  |  |  |  |  |
|  |  |  |  |  | 284 | 51050L500-029-G |  | MOS,N/N,Si1034CX-T1-GE3,20V,0.61A,G,SC-89-6,SMD | VISHAY ENTER TECHNO LOGY.INC | Si1034CX-T1-GE3 |  | G |  |  |  |  |  |  |  |
| Multi | ND |  | N | 285 | 285 | 51030QP00-237-G |  | MOS N,BSS138W-7-F,50V,0.2A,3.5ohm@10V,G,SOT323-3,SMD | DIODES INEORPORATION | BSS138W-7-F | 44 | G | Q1,Q9,Q10,Q11,Q13,Q14,Q24,Q25,Q26,Q27,Q28,Q29,Q30,Q31,Q32,Q33,Q34,Q35,Q36,Q37,Q38,Q39,Q40,Q41,Q42,Q43,Q44,Q45,Q46,Q47,Q48,Q49,Q50,Q51,Q52,Q53,Q54,Q55,Q56,Q57,Q58,Q59,Q60,Q93 |  |  |  |  |  |  |
|  |  |  |  |  | 285 | 51031KA00-031-G |  | MOS N,BSS138PW,60V,320mA, 2ohm@5V,G,SC70-3,SMD | NXP SEMICONDUCTORS | BSS138PW |  | G |  |  |  |  |  |  |  |
|  |  |  |  |  | 285 | 51031WU00-221-G |  | MOS N,BSS138W H6327,60V,280mA,3.5m@10V,G,SOT323-3,SMD | INFINEON TECHNOLOGIES CORP. | BSS138W H6327 |  | G |  |  |  |  |  |  |  |
| Multi | ND |  | N | 286 | 286 | 510406000-185-G |  | MOS P,FDD6685,30V,11A,30m@4.5V,G,TO252-3,SMD | FAIRCHILD SEMICONDUCTOR CORP | FDD6685 | 2 | G | Q5,Q7 |  |  |  |  |  |  |
|  |  |  |  |  | 286 | 510410G00-221-G |  | MOS P,IPD042P03L3 G,-30V,-70A,TO-252-3,SMD | INFINEON TECHNOLOGIES CORP. | IPD042P03L3 G |  | G |  |  |  |  |  |  |  |
|  |  |  |  |  | 286 | 51040WQ00-131-G |  | MOS P,TJ40S04M3L,-40V,-40A,9.1m@-10V,G,SMD-3 | TOSHIBA ELECTRONICS ASIA LTD | TJ40S04M3L |  | G |  |  |  |  |  |  |  |
| Multi | ND | ND | N | 287 | 287 | 510501900-237-G |  | MOS N/N,2N7002DW-7-F,60V,0.115A,7.5ohm@5V,G,SOT363-6,SMD | DIODES INEORPORATION | 2N7002DW-7-F | 1 | G | Q12 |  |  |  |  |  |  |
|  |  |  |  |  | 287 | 51050HV00-031-G |  | FET Dual channel,NX7002BKS,60V,240mA,2.8Ohm@Vgs=10V,3.2Ohm@Vgs=5V,SOT-363,6P,G | NXP SEMICONDUCTORS | NX7002BKS |  | G |  |  |  |  |  |  |  |
|  |  |  |  |  | 287 | 510329S00-131-G |  | MOS N,SSM6N7002KFU,LF(T,60V,300mA,1.5@10V,G,US6-6,SMD | TOSHIBA ELECTRONICS ASIA LTD | SSM6N7002KFU,LF(T |  | G |  |  |  |  |  |  |  |
| Multi | N |  | Y(5) | 288 | 288 | 61100QE00-017-G |  | RES,240 Ohm,+/-0.1%,1/16W,G,SMD0402 | KOA SPEER ELECTRONICS, INC. | RN731ETTP2400B25 | 4 | G | R3,R8,R365,R370 |  |  |  |  |  |  |
|  |  |  |  |  | 288 | 61100QE00-011-G |  | RES,240 Ohm,+/-0.1%,1/16W,G,SMD0402 | YAGEO CORPORATION COMPONENT | RT0402BRD07240RL |  | G |  |  |  |  |  |  |  |
|  |  |  |  |  | 288 | 61100QE00-044-G |  | RES,240 Ohm,+/-0.1%,1/16W,G,SMD0402 | TA-I TECHNOLOGY CO., LTD. | RB04BTP2400 |  | G |  |  |  |  |  |  |  |
| Multi | N | other | Y(4) | 289 | 289 | 610100T00-017-G |  | RES,1KOhm,+/-5%,1/16W,G,SMD0402 | KOA SPEER ELECTRONICS, INC. | RK73B1ETTP102J | 100 | G | R4,R5,R9,R10,R103,R129,R130,R131,R150,R151,R154,R171,R172,R175,R192,R193,R195,R213,R214,R215,R234,R235,R236,R255,R256,R259,R276,R277,R279,R318,R319,R366,R367,R371,R372,R455,R458,R484,R485,R486,R505,R506,R509,R526,R527,R530,R547,R548,R550,R568,R569,R570,R589,R590,R591,R611,R612,R615,R631,R632,R634,R1072,R1080,R1232,R1340,R1341,R1350,R1351,R1352,R1353,R1354,R1355,R1356,R1357,R1358,R1359,R1361,R1363,R1364,R1365,R1366,R1367,R1377,R1378,R1379,R1380,R1381,R1382,R1383,R1384,R1385,R1386,R1387,R1388,R1389,R1390,R1391,R1392,R1746,R1775 |  |  |  |  |  |  |
|  |  |  |  |  | 289 | 610100T00-024-G |  | RES,1KOhm,+/-5%,1/16W,G,SMD0402 | PANASONIC INDUSTRIAL CO.,LTD. | ERJ2GEJ102X |  | G |  |  |  |  |  |  |  |
|  |  |  |  |  | 289 | 610100T00-011-G |  | RES,1KOhm,+/-5%,1/16W,G,SMD0402 | YAGEO CORPORATION COMPONENT | RC0402JR-071KL |  | G |  |  |  |  |  |  |  |
|  |  |  |  |  | 289 | 610100T00-044-G |  | RES,1KOhm,+/-5%,1/16W,G,SMD0402 | TA-I TECHNOLOGY CO., LTD. | RM04JTN102 |  | G |  |  |  |  |  |  |  |
| Multi | ND | ND | Y(5) | 290 | 290 | 61100Y400-017-G |  | RES,169 Ohm,+/-0.1%,1/16W,G,SMD0402 | KOA SPEER ELECTRONICS, INC. | RN731ETTP1690B25 | 6 | G | R11,R12,R13,R373,R374,R375 |  |  |  |  |  |  |
|  |  |  |  |  | 290 | 61100Y400-011-G |  | RES,169Ohm,+/-0.1%,1/16W,SMD0402,G | YAGEO CORPORATION COMPONENT | RT0402BRD07169RL |  | G |  |  |  |  |  |  |  |
|  |  |  |  |  | 290 | 61100Y401-044-G |  | RES,169 Ohm,+/-0.1%,1/16W,G,SMD0402 | TA-I TECHNOLOGY CO., LTD. | RB04BTP1690 |  | G |  |  |  |  |  |  |  |
| Multi | N | ND | Y(4) | 291 | 291 | 610102700-017-G |  | RES,49.9 Ohm,+/-1%,1/16W,G,SMD0402 | KOA SPEER ELECTRONICS, INC. | RK73H1ETTP49R9F | 202 | G | R16,R17,R18,R19,R20,R21,R24,R25,R33,R34,R35,R36,R37,R46,R47,R48,R49,R50,R51,R65,R66,R69,R76,R94,R95,R99,R100,R101,R104,R105,R106,R107,R110,R111,R112,R113,R122,R138,R139,R140,R146,R147,R148,R155,R160,R161,R164,R166,R169,R177,R180,R182,R186,R187,R189,R197,R198,R203,R206,R207,R208,R222,R223,R224,R230,R231,R232,R240,R244,R245,R248,R250,R253,R261,R264,R266,R270,R271,R273,R281,R282,R287,R291,R292,R293,R376,R379,R380,R381,R382,R383,R386,R387,R391,R392,R395,R396,R397,R398,R400,R405,R406,R407,R408,R409,R410,R421,R422,R423,R424,R425,R426,R427,R432,R435,R436,R445,R446,R449,R453,R456,R457,R459,R460,R461,R493,R494,R495,R501,R502,R503,R510,R515,R516,R519,R521,R524,R533,R535,R537,R541,R542,R544,R552,R553,R558,R561,R562,R563,R577,R578,R579,R585,R586,R587,R594,R599,R600,R603,R605,R608,R610,R617,R621,R625,R626,R628,R636,R637,R642,R645,R646,R647,R740,R748,R933,R935,R1346,R1348,R1349,R1368,R1371,R1374,R1396,R1397,R1401,R1402,R1408,R1409,R1410,R1411,R1419,R1420,R1421,R1429,R1430,R1431,R1591,R1822,R1827,R1828,R1829 |  |  |  |  |  |  |
|  |  |  |  |  | 291 | 610102700-029-G |  | RES,49.9 Ohm,+/-1%,1/16W,G,SMD0402 | VISHAY ENTER TECHNO LOGY.INC | CRCW040249R9FKED |  | G |  |  |  |  |  |  |  |
|  |  |  |  |  | 291 | 610102700-024-G |  | RES,49.9 Ohm,+/-1%,1/16W,G,SMD0402 | PANASONIC INDUSTRIAL CO.,LTD. | ERJ2RKF49R9X |  | G |  |  |  |  |  |  |  |
|  |  |  |  |  | 291 | 610102700-011-G |  | RES,49.9 Ohm,+/-1%,1/16W,G,SMD0402 | YAGEO CORPORATION COMPONENT | RC0402FR-0749R9L |  | G |  |  |  |  |  |  |  |
|  |  |  |  |  | 291 | 610102700-044-G |  | RES,49.9 Ohm,+/-1%,1/16W,G,SMD0402 | TA-I TECHNOLOGY CO., LTD. | RM04FTN49R9 |  | G |  |  |  |  |  |  |  |
| Multi |  |  | Y(4) | 292 | 292 | 61010KJ00-017-G |  | RES,3.3KOhm,+/-5%,1/16W,G,SMD0402 | KOA SPEER ELECTRONICS, INC. | RK73B1ETTP332J | 82 | G | R22,R23,R26,R32,R38,R39,R41,R42,R43,R44,R45,R52,R68,R88,R89,R299,R300,R301,R302,R342,R384,R385,R388,R389,R390,R394,R399,R401,R403,R404,R411,R412,R413,R441,R442,R465,R466,R468,R469,R472,R475,R476,R954,R1029,R1031,R1032,R1033,R1034,R1035,R1041,R1042,R1043,R1044,R1047,R1048,R1050,R1051,R1054,R1055,R1059,R1060,R1063,R1064,R1067,R1068,R1127,R1128,R1139,R1141,R1225,R1227,R1229,R1234,R1239,R1336,R1337,R1466,R1468,R1524,R1525,R1553,R1823 |  |  |  |  |  |  |
|  |  |  |  |  | 292 | 61010KJ00-024-G |  | RES,3.3KOhm,+/-5%,1/16W,G,SMD0402 | PANASONIC INDUSTRIAL CO.,LTD. | ERJ2GEJ332X |  | G |  |  |  |  |  |  |  |
|  |  |  |  |  | 292 | 61010KJ00-044-G |  | RES,3.3KOhm,+/-5%,1/16W,G,SMD0402 | TA-I TECHNOLOGY CO., LTD. | RM04JTN332 |  | G |  |  |  |  |  |  |  |
|  |  |  |  |  | 292 | 61010KJ00-011-G |  | RES,3.3KOhm,+/-5%,1/16W,G,SMD0402 | YAGEO CORPORATION COMPONENT | RC0402JR-073K3L |  | G |  |  |  |  |  |  |  |
| Multi | ND | ND | Y(4) | 293 | 293 | 610115E00-017-G |  | RES,1.2KOhm,+/-5%,1/16W,G,SMD0402 | KOA SPEER ELECTRONICS, INC. | RK73B1ETTP122J | 12 | G | R27,R28,R54,R55,R56,R57,R58,R59,R417,R418,R419,R420 |  |  |  |  |  |  |
|  |  |  |  |  | 293 | 610115E00-024-G |  | RES,1.2KOhm,+/-5%,1/16W,G,SMD0402 | PANASONIC INDUSTRIAL CO.,LTD. | ERJ2GEJ122X |  | G |  |  |  |  |  |  |  |
|  |  |  |  |  | 293 | 610115E00-011-G |  | RES,1.2KOhm,+/-5%,1/16W,G,SMD0402 | YAGEO CORPORATION COMPONENT | RC0402JR-071K2L |  | G |  |  |  |  |  |  |  |
|  |  |  |  |  | 293 | 610115E00-044-G |  | RES,1.2KOhm,+/-5%,1/16W,G,SMD0402 | TA-I TECHNOLOGY CO., LTD. | RM04JTN122 |  | G |  |  |  |  |  |  |  |
| Multi | ND |  | Y(5) | 294 | 294 | 61100V600-017-G |  | RES,200 Ohm,+/-0.1%,1/16W,G,SMD0402 | KOA SPEER ELECTRONICS, INC. | RN731ETTP2000B25 | 6 | G | R31,R40,R53,R393,R402,R416 |  |  |  |  |  |  |
|  |  |  |  |  | 294 | 61100V600-011-G |  | RES,200 Ohm,+/-0.1%,1/16W,G,SMD0402 | YAGEO CORPORATION COMPONENT | RT0402BRD07200RL |  | G |  |  |  |  |  |  |  |
| Multi | N | Other | Y(4) | 295 | 295 | 610115T00-017-G |  | RES,40.2KOhm,+/-1%,1/16W,G,SMD0402 | KOA SPEER ELECTRONICS, INC. | RK73H1ETTP4022F | 1 | G | R78 |  |  |  |  |  |  |
|  |  |  |  |  | 295 | 610115T00-029-G |  | RES,40.2KOhm,+/-1%,1/16W,G,SMD0402 | VISHAY ENTER TECHNO LOGY.INC | CRCW040240K2FKEDC |  | G |  |  |  |  |  |  |  |
|  |  |  |  |  | 295 | 610115T00-011-G |  | RES,40.2KOhm,+/-1%,1/16W,G,SMD0402 | YAGEO CORPORATION COMPONENT | RC0402FR-0740K2L |  | G |  |  |  |  |  |  |  |
|  |  |  |  |  | 295 | 610115T00-044-G |  | RES,40.2KOhm,+/-1%,1/16W,G,SMD0402 | TA-I TECHNOLOGY CO., LTD. | RM04FTN4022 |  | G |  |  |  |  |  |  |  |
| Multi |  |  | Y(4) | 296 | 296 | 610112W00-017-G |  | RES,2KOhm,+/-5%,1/16W,G,SMD0402 | KOA SPEER ELECTRONICS, INC. | RK73B1ETTP202J | 5 | G | R97,R98,R447,R452,R454 |  |  |  |  |  |  |
|  |  |  |  |  | 296 | 610112W00-024-G |  | RES,2KOhm,+/-5%,1/16W,G,SMD0402 | PANASONIC INDUSTRIAL CO.,LTD. | ERJ2GEJ202X |  | G |  |  |  |  |  |  |  |
|  |  |  |  |  | 296 | 610112W00-011-G |  | RES,2KOhm,+/-5%,1/16W,G,SMD0402 | YAGEO CORPORATION COMPONENT | RC0402JR-072KL |  | G |  |  |  |  |  |  |  |
|  |  |  |  |  | 296 | 610112W00-044-G |  | RES,2KOhm,+/-5%,1/16W,G,SMD0402 | TA-I TECHNOLOGY CO., LTD. | RM04JTN202 |  | G |  |  |  |  |  |  |  |
| Multi | N | ND | Y(4) | 297 | 297 | 61010DL01-017-G |  | RES,0 Ohm,+/-5%,1/8W,G,SMD0805 | KOA SPEER ELECTRONICS, INC. | RK73Z2ATTD | 4 | G | R108,R109,R463,R464 |  |  |  |  |  |  |
|  |  |  |  |  | 297 | 61010DL00-024-G |  | RES,0 Ohm,+/-5%,1/8W,G,SMD0805 | PANASONIC INDUSTRIAL CO.,LTD. | ERJ6GEY0R00V |  | G |  |  |  |  |  |  |  |
|  |  |  |  |  | 297 | 61010DL00-011-G |  | RES,0 Ohm,+/-5%,1/8W,G,SMD0805 | YAGEO CORPORATION COMPONENT | RC0805JR-070RL |  | G |  |  |  |  |  |  |  |
|  |  |  |  |  | 297 | 61010DL00-044-G |  | RES,0 Ohm,+/-5%,1/8W,G,SMD0805 | TA-I TECHNOLOGY CO., LTD. | RM10JTN0 |  | G |  |  |  |  |  |  |  |
| Single | ND | ND | Y(4) | 298 | 298 | 610102C00-017-G |  | RES,15KOhm,+/-5%,1/16W,G,SMD0402 | KOA SPEER ELECTRONICS, INC. | RK73B1ETTP153J | 18 | G | R123,R124,R125,R126,R127,R128,R327,R829,R835,R836,R1125,R1513,R1542,R1543,R1544,R1545,R1546,R1547 |  |  |  |  |  |  |
| Multi | N | other | Y(4) | 299 | 299 | 610102E00-017-G |  | RES,100 Ohm,+/-5%,1/16W,G,SMD0402 | KOA SPEER ELECTRONICS, INC. | RK73B1ETTP101J | 65 | G | R132,R137,R141,R143,R152,R158,R162,R167,R173,R179,R183,R188,R194,R200,R204,R209,R216,R221,R225,R227,R237,R239,R246,R251,R257,R263,R267,R272,R278,R284,R288,R290,R487,R492,R496,R498,R507,R513,R517,R522,R528,R531,R538,R543,R549,R555,R559,R564,R571,R576,R580,R582,R592,R597,R601,R606,R613,R620,R622,R627,R633,R639,R643,R648,R934 |  |  |  |  |  |  |
|  |  |  |  |  | 299 | 610102E00-029-G |  | RES,100 Ohm,+/-5%,1/16W,G,SMD0402 | VISHAY ENTER TECHNO LOGY.INC | CRCW0402100RJNED |  | G |  |  |  |  |  |  |  |
|  |  |  |  |  | 299 | 610102E00-011-G |  | RES,100 Ohm,+/-5%,1/16W,G,SMD0402 | YAGEO CORPORATION COMPONENT | RC0402JR-07100RL |  | G |  |  |  |  |  |  |  |
|  |  |  |  |  | 299 | 610102E00-044-G |  | RES,100 Ohm,+/-5%,1/16W,G,SMD0402 | TA-I TECHNOLOGY CO., LTD. | RM04JTN101 |  | G |  |  |  |  |  |  |  |
| Multi | N | ND | Y(4) | 300 | 300 | 610107B00-017-G |  | RES,4.7KOhm,+/-5%,1/16W,G,SMD0402 | KOA SPEER ELECTRONICS, INC. | RK73B1ETTP472J | 7 | G | R297,R298,R304,R1069,R1070,R1342,R1343 |  |  |  |  |  |  |
|  |  |  |  |  | 300 | 610107B00-024-G |  | RES,4.7KOhm,+/-5%,1/16W,G,SMD0402 | PANASONIC INDUSTRIAL CO.,LTD. | ERJ2GEJ472X |  | G |  |  |  |  |  |  |  |
|  |  |  |  |  | 300 | 610107B00-029-G |  | RES,4.7KOhm,+/-5%,1/16W,G,SMD0402 | VISHAY ENTER TECHNO LOGY.INC | CRCW04024K70JNED |  | G |  |  |  |  |  |  |  |
|  |  |  |  |  | 300 | 610107B00-011-G |  | RES,4.7KOhm,+/-5%,1/16W,G,SMD0402 | YAGEO CORPORATION COMPONENT | RC0402JR-074K7L |  | G |  |  |  |  |  |  |  |
|  |  |  |  |  | 300 | 610107B00-044-G |  | RES,4.7KOhm,+/-5%,1/16W,G,SMD0402 | TA-I TECHNOLOGY CO., LTD. | RM04JTN472 |  | G |  |  |  |  |  |  |  |
| Multi | ND | ND | Y(4) | 301 | 301 | 610112U00-017-G |  | RES,499 Ohm,+/-1%,1/16W,G,SMD0402 | KOA SPEER ELECTRONICS, INC. | RK73H1ETTP4990F | 1 | G | R307 |  |  |  |  |  |  |
|  |  |  |  |  | 301 | 610112U00-024-G |  | RES,499 Ohm,+/-1%,1/16W,G,SMD0402 | PANASONIC INDUSTRIAL CO.,LTD. | ERJ2RKF4990X |  | G |  |  |  |  |  |  |  |
|  |  |  |  |  | 301 | 610112U00-011-G |  | RES,499 Ohm,+/-1%,1/16W,G,SMD0402 | YAGEO CORPORATION COMPONENT | RC0402FR-07499RL |  | G |  |  |  |  |  |  |  |
|  |  |  |  |  | 301 | 610112U00-044-G |  | RES,499 Ohm,+/-1%,1/16W,G,SMD0402 | TA-I TECHNOLOGY CO., LTD. | RM04FTN4990 |  | G |  |  |  |  |  |  |  |
| Multi | N | other | Y(4) | 302 | 302 | 610107C00-017-G |  | RES,10KOhm,+/-5%,1/16W,G,SMD0402 | KOA SPEER ELECTRONICS, INC. | RK73B1ETTP103J | 2 | G | R310,R990 |  |  |  |  |  |  |
|  |  |  |  |  | 302 | 610107C00-024-G |  | RES,10KOhm,+/-5%,1/16W,G,SMD0402 | PANASONIC INDUSTRIAL CO.,LTD. | ERJ2GEJ103X |  | G |  |  |  |  |  |  |  |
|  |  |  |  |  | 302 | 610107C00-029-G |  | RES,10KOhm,+/-5%,1/16W,G,SMD0402 | VISHAY ENTER TECHNO LOGY.INC | CRCW040210K0JNED |  | G |  |  |  |  |  |  |  |
|  |  |  |  |  | 302 | 610107C00-011-G |  | RES,10KOhm,+/-5%,1/16W,G,SMD0402 | YAGEO CORPORATION COMPONENT | RC0402JR-0710KL |  | G |  |  |  |  |  |  |  |
|  |  |  |  |  | 302 | 610107C00-044-G |  | RES,10KOhm,+/-5%,1/16W,G,SMD0402 | TA-I TECHNOLOGY CO., LTD. | RM04JTN103 |  | G |  |  |  |  |  |  |  |
| Multi | ND | ND | Y(4) | 303 | 303 | 61011MW00-017-G |  | RES,31.6KOhm,+/-1%,1/16W,G,SMD0402 | KOA SPEER ELECTRONICS, INC. | RK73H1ETTP3162F | 1 | G | R328 |  |  |  |  |  |  |
|  |  |  |  |  | 303 | 61011MW00-011-G |  | RES,31.6KOhm,+/-1%,1/16W,G,SMD0402 | YAGEO CORPORATION COMPONENT | RC0402FR-0731K6L |  | G |  |  |  |  |  |  |  |
|  |  |  |  |  | 303 | 61011MW00-044-G |  | RES,31.6KOhm,+/-1%,1/16W,G,SMD0402 | TA-I TECHNOLOGY CO., LTD. | RM04FTN3162 |  | G |  |  |  |  |  |  |  |
| Multi | ND | ND | Y(4) | 304 | 304 | 610118G00-017-G |  | RES,90.9KOhm,+/-1%,1/16W,G,SMD0402 | KOA SPEER ELECTRONICS, INC. | RK73H1ETTP9092F | 1 | G | R329 |  |  |  |  |  |  |
|  |  |  |  |  | 304 | 610118G00-024-G |  | RES,90.9KOhm,+/-1%,1/16W,G,SMD0402 | PANASONIC INDUSTRIAL CO.,LTD. | ERJ2RKF9092X |  | G |  |  |  |  |  |  |  |
|  |  |  |  |  | 304 | 610118G00-011-G |  | RES,90.9KOhm,+/-1%,1/16W,G,SMD0402 | YAGEO CORPORATION COMPONENT | RC0402FR-0790K9L |  | G |  |  |  |  |  |  |  |
|  |  |  |  |  | 304 | 610118G00-044-G |  | RES,90.9KOhm,+/-1%,1/16W,G,SMD0402 | TA-I TECHNOLOGY CO., LTD. | RM04FTN9092 |  | G |  |  |  |  |  |  |  |
| Multi | N | ND | Y(4) | 305 | 305 | 610116J00-017-G |  | RES,1.21KOhm,+/-1%,1/16W,G,SMD0402 | KOA SPEER ELECTRONICS, INC. | RK73H1ETTP1211F | 13 | G | R332,R333,R334,R335,R336,R337,R338,R339,R340,R341,R343,R344,R345 |  |  |  |  |  |  |
|  |  |  |  |  | 305 | 610116J00-024-G |  | RES,1.21KOhm,+/-1%,1/16W,G,SMD0402 | PANASONIC INDUSTRIAL CO.,LTD. | ERJ2RKF1211X |  | G |  |  |  |  |  |  |  |
|  |  |  |  |  | 305 | 610116J00-029-G |  | RES,1.21KOhm,+/-1%,1/16W,G,SMD0402 | VISHAY ENTER TECHNO LOGY.INC | CRCW04021K21FKED |  | G |  |  |  |  |  |  |  |
|  |  |  |  |  | 305 | 610116J00-011-G |  | RES,1.21KOhm,+/-1%,1/16W,G,SMD040 | YAGEO CORPORATION COMPONENT | RC0402FR-071K21L |  | G |  |  |  |  |  |  |  |
|  |  |  |  |  | 305 | 610116J00-044-G |  | RES,1.21KOhm,+/-1%,1/16W,G,SMD0402 | TA-I TECHNOLOGY CO., LTD. | RM04FTN1211 |  | G |  |  |  |  |  |  |  |
| Multi | N | Other | Y(4) | 306 | 306 | 610114W00-017-G |  | RES,3.01KOhm,+/-1%,1/16W,G,SMD0402 | KOA SPEER ELECTRONICS, INC. | RK73H1ETTP3011F | 1 | G | R346 |  |  |  |  |  |  |
|  |  |  |  |  | 306 | 610114W00-029-G |  | RES,3.01KOhm,+/-1%,1/16W,G,SMD0402 | VISHAY ENTER TECHNO LOGY.INC | CRCW04023K01FKED |  | G |  |  |  |  |  |  |  |
|  |  |  |  |  | 306 | 610114W00-011-G |  | RES,3.01KOhm,+/-1%,1/16W,G,SMD0402 | YAGEO CORPORATION COMPONENT | RC0402FR-073K01L |  | G |  |  |  |  |  |  |  |
|  |  |  |  |  | 306 | 610114W00-044-G |  | RES,3.01KOhm,+/-1%,1/16W,G,SMD0402 | TA-I TECHNOLOGY CO., LTD. | RM04FTN3011 |  | G |  |  |  |  |  |  |  |
| Multi | ND | ND | Y(4) | 307 | 307 | 61010L600-017-G |  | RES,11KOhm,+/-1%,1/16W,G,SMD0402 | KOA SPEER ELECTRONICS, INC. | RK73H1ETTP1102F | 1 | G | R349 |  |  |  |  |  |  |
|  |  |  |  |  | 307 | 61010L600-024-G |  | RES,11KOhm,+/-1%,1/16W,G,SMD0402 | PANASONIC INDUSTRIAL CO.,LTD. | ERJ2RKF1102X |  | G |  |  |  |  |  |  |  |
|  |  |  |  |  | 307 | 61010L600-029-G |  | RES,11KOhm,+/-1%,1/16W,G,SMD0402 | VISHAY ENTER TECHNO LOGY.INC | CRCW040211K0FKEDC |  | G |  |  |  |  |  |  |  |
|  |  |  |  |  | 307 | 61010L600-011-G |  | RES,11KOhm,+/-1%,1/16W,G,SMD0402 | YAGEO CORPORATION COMPONENT | RC0402FR-0711KL |  | G |  |  |  |  |  |  |  |
|  |  |  |  |  | 307 | 61010L600-044-G |  | RES,11KOhm,+/-1%,1/16W,G,SMD0402 | TA-I TECHNOLOGY CO., LTD. | RM04FTN1102 |  | G |  |  |  |  |  |  |  |
| Multi | ND | ND | Y(4) | 308 | 308 | 61011B000-017-G |  | RES,1.5KOhm,+/-1%,1/16W,G,SMD0402 | KOA SPEER ELECTRONICS, INC. | RK73H1ETTP1501F | 2 | G | R738,R1111 |  |  |  |  |  |  |
|  |  |  |  |  | 308 | 61011B000-024-G |  | RES,1.5KOhm,+/-1%,1/16W,G,SMD0402 | PANASONIC INDUSTRIAL CO.,LTD. | ERJ2RKF1501X |  | G |  |  |  |  |  |  |  |
|  |  |  |  |  | 308 | 61011B000-011-G |  | RES,1.5KOhm,+/-1%,1/16W,G,SMD0402 | YAGEO CORPORATION COMPONENT | RC0402FR-071K5L |  | G |  |  |  |  |  |  |  |
|  |  |  |  |  | 308 | 61011B000-044-G |  | RES,1.5KOhm,+/-1%,1/16W,G,SMD0402 | TA-I TECHNOLOGY CO., LTD. | RM04FTN1501 |  | G |  |  |  |  |  |  |  |
| Multi | N | ND | Y(4) | 309 | 309 | 610101V00-017-G |  | RES,22 Ohm,+/-5%,1/16W,G,SMD0402 | KOA SPEER ELECTRONICS, INC. | RK73B1ETTP220J | 12 | G | R739,R741,R742,R743,R749,R936,R937,R993,R994,R995,R996,R997 |  |  |  |  |  |  |
|  |  |  |  |  | 309 | 610101V00-024-G |  | RES,22 Ohm,+/-5%,1/16W,G,SMD0402 | PANASONIC INDUSTRIAL CO.,LTD. | ERJ2GEJ220X |  | G |  |  |  |  |  |  |  |
|  |  |  |  |  | 309 | 610101V00-011-G |  | RES,22 Ohm,+/-5%,1/16W,G,SMD0402 | YAGEO CORPORATION COMPONENT | RC0402JR-0722RL |  | G |  |  |  |  |  |  |  |
|  |  |  |  |  | 309 | 610101V00-044-G |  | RES,22 Ohm,+/-5%,1/16W,G,SMD0402 | TA-I TECHNOLOGY CO., LTD. | RM04JTN220 |  | G |  |  |  |  |  |  |  |
| Single | ND |  | Y(5) | 310 | 310 | 61100H601-017-G |  | RES,2KOhm,+/-0.5%,1/16W,G,SMD0402 | KOA SPEER ELECTRONICS, INC. | RN731ETTP2001D25 | 1 | G | R751 |  |  |  |  |  |  |
| Multi | ND | ND | Y(4) | 311 | 311 | 610112L00-017-G |  | RES,1.24KOhm,+/-1%,1/16W,G,SMD0402 | KOA SPEER ELECTRONICS, INC. | RK73H1ETTP1241F | 1 | G | R753 |  |  |  |  |  |  |
|  |  |  |  |  | 311 | 610112L00-029-G |  | RES,1.24KOhm,+/-1%,1/16W,G,SMD0402 | VISHAY ENTER TECHNO LOGY.INC | CRCW04021K24FKED |  | G |  |  |  |  |  |  |  |
|  |  |  |  |  | 311 | 610112L00-024-G |  | RES,1.24KOhm,+/-1%,1/16W,G,SMD0402 | PANASONIC INDUSTRIAL CO.,LTD. | ERJ2RKF1241X |  | G |  |  |  |  |  |  |  |
|  |  |  |  |  | 311 | 610112L00-011-G |  | RES,1.24KOhm,+/-1%,1/16W,G,SMD0402 | YAGEO CORPORATION COMPONENT | RC0402FR-071K24L |  | G |  |  |  |  |  |  |  |
|  |  |  |  |  | 311 | 610112L00-044-G |  | RES,1.24KOhm,+/-1%,1/16W,G,SMD0402 | TA-I TECHNOLOGY CO., LTD. | RM04FTN1241 |  | G |  |  |  |  |  |  |  |
| Multi | ND | ND | Y(4) | 312 | 312 | 61011T800-017-G |  | RES,240 Ohm,+/-1%,1/16W,G,SMD0402 | KOA SPEER ELECTRONICS, INC. | RK73H1ETTP2400F | 1 | G | R789 |  |  |  |  |  |  |
|  |  |  |  |  | 312 | 61011T800-011-G |  | RES,240 Ohm,+/-1%,1/16W,G,SMD0402 | YAGEO CORPORATION COMPONENT | RC0402FR-07240RL |  | G |  |  |  |  |  |  |  |
|  |  |  |  |  | 312 | 61011T800-044-G |  | RES,240 Ohm,+/-1%,1/16W,G,SMD0402 | TA-I TECHNOLOGY CO., LTD. | RM04FTN2400 |  | G |  |  |  |  |  |  |  |
| Multi | ND | ND | Y(5) | 313 | 313 | 61100BN00-017-G |  | RES,100KOhm,+/-1%,1/16W,G,SMD0402 | KOA SPEER ELECTRONICS, INC. | RN731ETTP1003F25 | 4 | G | R790,R1154,R1157,R1237 |  |  |  |  |  |  |
|  |  |  |  |  | 313 | 61100BN00-011-G |  | RES,100KOhm,+/-1%,1/16W,G,SMD0402 | YAGEO CORPORATION COMPONENT | RT0402FRD07100KL |  | G |  |  |  |  |  |  |  |
| Multi | N | ND | Y(4) | 314 | 314 | 610115J00-017-G |  | RES,33 Ohm,+/-1%,1/16W,G,SMD0402 | KOA SPEER ELECTRONICS, INC. | RK73H1ETTP33R0F | 9 | G | R792,R793,R794,R796,R797,R799,R925,R927,R929 |  |  |  |  |  |  |
|  |  |  |  |  | 314 | 610115J00-024-G |  | RES,33 Ohm,+/-1%,1/16W,G,SMD0402 | PANASONIC INDUSTRIAL CO.,LTD. | ERJ2RKF33R0X |  | G |  |  |  |  |  |  |  |
|  |  |  |  |  | 314 | 610115J00-011-G |  | RES,33 Ohm,+/-1%,1/16W,G,SMD0402 | YAGEO CORPORATION COMPONENT | RC0402FR-0733RL |  | G |  |  |  |  |  |  |  |
|  |  |  |  |  | 314 | 610115J00-044-G |  | RES,33 Ohm,+/-1%,1/16W,G,SMD0402 | TA-I TECHNOLOGY CO., LTD. | RM04FTN33R0 |  | G |  |  |  |  |  |  |  |
| Multi | ND | ND | Y(4) | 315 | 315 | 61011H500-017-G |  | RES,22 Ohm,+/-1%,1/16W,G,SMD0402 | KOA SPEER ELECTRONICS, INC. | RK73H1ETTP22R0F | 24 | G | R815,R816,R818,R1015,R1161,R1163,R1171,R1173,R1183,R1189,R1196,R1202,R1206,R1209,R1226,R1307,R1314,R1315,R1316,R1317,R1318,R1319,R1320,R1502 |  |  |  |  |  |  |
|  |  |  |  |  | 315 | 61011H500-024-G |  | RES,22 Ohm,+/-1%,1/16W,G,SMD0402 | PANASONIC INDUSTRIAL CO.,LTD. | ERJ2RKF22R0X |  | G |  |  |  |  |  |  |  |
|  |  |  |  |  | 315 | 61011H500-011-G |  | RES,22 Ohm,+/-1%,1/16W,G,SMD0402 | YAGEO CORPORATION COMPONENT | RC0402FR-0722RL |  | G |  |  |  |  |  |  |  |
|  |  |  |  |  | 315 | 61011H500-044-G |  | RES,22 Ohm,+/-1%,1/16W,G,SMD0402 | TA-I TECHNOLOGY CO., LTD. | RM04FTN22R0 |  | G |  |  |  |  |  |  |  |
| Multi | ND | ND | Y(4) | 316 | 316 | 61011H100-017-G |  | RES,220 Ohm,+/-1%,1/16W,G,SMD0402 | KOA SPEER ELECTRONICS, INC. | RK73H1ETTP2200F | 7 | G | R831,R832,R833,R834,R1345,R1347,R1494 |  |  |  |  |  |  |
|  |  |  |  |  | 316 | 61011H100-024-G |  | RES,220 Ohm,+/-1%,1/16W,G,SMD0402 | PANASONIC INDUSTRIAL CO.,LTD. | ERJ2RKF2200X |  | G |  |  |  |  |  |  |  |
|  |  |  |  |  | 316 | 61011H100-029-G |  | RES,220 Ohm,+/-1%,1/16W,G,SMD0402 | VISHAY ENTER TECHNO LOGY.INC | CRCW0402220RFKEDC |  | G |  |  |  |  |  |  |  |
|  |  |  |  |  | 316 | 61011H100-011-G |  | RES,220 Ohm,+/-1%,1/16W,G,SMD0402 | YAGEO CORPORATION COMPONENT | RC0402FR-07220RL |  | G |  |  |  |  |  |  |  |
| Multi | ND |  | Y(4) | 317 | 317 | 61011U901-017-G |  | RES,120Ohm,+/-1%,1/20W,G,SMD0201 | KOA SPEER ELECTRONICS, INC. | RK73H1HTTC1200F | 48 | G | R839,R840,R841,R842,R843,R844,R845,R846,R847,R848,R849,R850,R851,R852,R853,R854,R855,R856,R857,R858,R859,R860,R861,R862,R867,R868,R869,R870,R871,R872,R873,R874,R875,R876,R877,R878,R879,R880,R881,R882,R883,R884,R885,R887,R888,R889,R890,R891 |  |  |  |  |  |  |
|  |  |  |  |  | 317 | 61011U900-011-G |  | RES,120Ohm,+/-1%,1/20W,SMD0201,G | YAGEO CORPORATION COMPONENT | RC0201FR-07120RL |  | G |  |  |  |  |  |  |  |
| Multi | ND | ND | Y(4) | 318 | 318 | 61011KH00-017-G |  | RES,240 Ohm,+/-5%,1/16W,G,SMD0402 | KOA SPEER ELECTRONICS, INC. | RK73B1ETTP241J | 1 | G | R886 |  |  |  |  |  |  |
|  |  |  |  |  | 318 | 61011KH00-024-G |  | RES,240 Ohm,+/-5%,1/16W,G,SMD0402 | PANASONIC INDUSTRIAL CO.,LTD. | ERJ2GEJ241X |  | G |  |  |  |  |  |  |  |
|  |  |  |  |  | 318 | 61011KH00-011-G |  | RES,240 Ohm,+/-5%,1/16W,G,SMD0402 | YAGEO CORPORATION COMPONENT | RC0402JR-07240RL |  | G |  |  |  |  |  |  |  |
|  |  |  |  |  | 318 | 61011KH00-044-G |  | RES,240 Ohm,+/-5%,1/16W,G,SMD0402 | TA-I TECHNOLOGY CO., LTD. | RM04JTN241 |  | G |  |  |  |  |  |  |  |
| Multi | N |  | Y(5) | 319 | 319 | 61100LV00-017-G |  | RES,10KOhm,+/-1%,1/16W,G,SMD0402 | KOA SPEER ELECTRONICS, INC. | RN731ETTP1002F50 | 9 | G | R940,R966,R998,R999,R1084,R1085,R1088,R1261,R1751 |  |  |  |  |  |  |
|  |  |  |  |  | 319 | 61100LV00-011-G |  | RES,10KOhm,+/-1%,1/16W,G,SMD0402 | YAGEO CORPORATION COMPONENT | RT0402FRE0710KL |  | G |  |  |  |  |  |  |  |
|  |  |  |  |  | 319 | 61100LV00-044-G |  | RES,10KOhm,+/-1%,1/16W,G,SMD0402 | TA-I TECHNOLOGY CO., LTD. | RB04FTS1002 |  | G |  |  |  |  |  |  |  |
| Multi | ND | ND | Y(4) | 320 | 320 | 610114U00-017-G |  | RES,3.3KOhm,+/-1%,1/16W,G,SMD0402 | KOA SPEER ELECTRONICS, INC. | RK73H1ETTP3301F | 21 | G | R960,R1323,R1325,R1327,R1328,R1412,R1413,R1414,R1416,R1417,R1418,R1422,R1423,R1424,R1426,R1427,R1428,R1505,R1506,R1523,R1783 |  |  |  |  |  |  |
|  |  |  |  |  | 320 | 610114U00-024-G |  | RES,3.3KOhm,+/-1%,1/16W,G,SMD0402 | PANASONIC INDUSTRIAL CO.,LTD. | ERJ2RKF3301X |  | G |  |  |  |  |  |  |  |
|  |  |  |  |  | 320 | 610114U00-011-G |  | RES,3.3KOhm,+/-1%,1/16W,G,SMD0402 | YAGEO CORPORATION COMPONENT | RC0402FR-073K3L |  | G |  |  |  |  |  |  |  |
|  |  |  |  |  | 320 | 610114U00-044-G |  | RES,3.3KOhm,+/-1%,1/16W,G,SMD0402 | TA-I TECHNOLOGY CO., LTD. | RM04FTN3301 |  | G |  |  |  |  |  |  |  |
| Multi | ND | ND | Y(5) | 321 | 321 | 61100C600-017-G |  | RES,1KOhm,+/-0.5%,1/16W,G,SMD0402 | KOA SPEER ELECTRONICS, INC. | RN731ETTP1001D25 | 19 | G | R961,R962,R963,R964,R965,R967,R968,R969,R970,R975,R976,R977,R978,R985,R986,R988,R989,R992,R1003 |  |  |  |  |  |  |
|  |  |  |  |  | 321 | 61100C603-024-G |  | RES,1KOhm,+/-0.5%,1/16W,G,SMD0402 | PANASONIC INDUSTRIAL CO.,LTD. | ERA2AED102X |  | G |  |  |  |  |  |  |  |
| Multi | N | ND | Y(4) | 322 | 322 | 61010A000-017-G |  | RES,8.2KOhm,+/-5%,1/16W,G,SMD0402 | KOA SPEER ELECTRONICS, INC. | RK73B1ETTP822J | 1 | G | R971 |  |  |  |  |  |  |
|  |  |  |  |  | 322 | 61010A000-024-G |  | RES,8.2KOhm,+/-5%,1/16W,G,SMD0402 | PANASONIC INDUSTRIAL CO.,LTD. | ERJ2GEJ822X |  | G |  |  |  |  |  |  |  |
|  |  |  |  |  | 322 | 61010A000-011-G |  | RES,8.2KOhm,+/-5%,1/16W,G,SMD0402 | YAGEO CORPORATION COMPONENT | RC0402JR-078K2L |  | G |  |  |  |  |  |  |  |
|  |  |  |  |  | 322 | 61010A000-044-G |  | RES,8.2KOhm,+/-5%,1/16W,G,SMD0402 | TA-I TECHNOLOGY CO., LTD. | RM04JTN822 |  | G |  |  |  |  |  |  |  |
| Multi | ND | ND | Y(4) | 323 | 323 | 610115V00-017-G |  | RES,300 Ohm,+/-1%,1/16W,G,SMD0402 | KOA SPEER ELECTRONICS, INC. | RK73H1ETTP3000F | 48 | G | R991,R1440,R1446,R1447,R1448,R1449,R1450,R1451,R1594,R1595,R1596,R1597,R1598,R1601,R1602,R1607,R1608,R1609,R1610,R1611,R1612,R1613,R1614,R1615,R1616,R1617,R1618,R1619,R1620,R1621,R1622,R1623,R1624,R1625,R1626,R1627,R1628,R1629,R1630,R1631,R1632,R1633,R1634,R1635,R1636,R1637,R1638,R1723 |  |  |  |  |  |  |
|  |  |  |  |  | 323 | 610115V00-011-G |  | RES,300 Ohm,+/-1%,1/16W,G,SMD0402 | YAGEO CORPORATION COMPONENT | RC0402FR-07300RL |  | G |  |  |  |  |  |  |  |
|  |  |  |  |  | 323 | 610115V00-044-G |  | RES,300 Ohm,+/-1%,1/16W,G,SMD0402 | TA-I TECHNOLOGY CO., LTD. | RM04FTN3000 |  | G |  |  |  |  |  |  |  |
| Multi | N | ND | Y(4) | 324 | 324 | 610118100-017-G |  | RES,1.4KOhm,+/-1%,1/16W,G,SMD0402 | KOA SPEER ELECTRONICS, INC. | RK73H1ETTP1401F | 2 | G | R1000,R1002 |  |  |  |  |  |  |
|  |  |  |  |  | 324 | 610118100-024-G |  | RES,1.4KOhm,+/-1%,1/16W,G,SMD0402 | PANASONIC INDUSTRIAL CO.,LTD. | ERJ2RKF1401X |  | G |  |  |  |  |  |  |  |
|  |  |  |  |  | 324 | 610118100-011-G |  | RES,1.4KOhm,+/-1%,1/16W,G,SMD0402 | YAGEO CORPORATION COMPONENT | RC0402FR-071K4L |  | G |  |  |  |  |  |  |  |
|  |  |  |  |  | 324 | 610118100-044-G |  | RES,1.4KOhm,+/-1%,1/16W,G,SMD0402 | TA-I TECHNOLOGY CO., LTD. | RM04FTN1401 |  | G |  |  |  |  |  |  |  |
| Multi | N | Other | Y(4) | 325 | 325 | 610114R00-017-G |  | RES,49.9KOhm,+/-1%,1/16W,G,SMD0402 | KOA SPEER ELECTRONICS, INC. | RK73H1ETTP4992F | 1 | G | R1026 |  |  |  |  |  |  |
|  |  |  |  |  | 325 | 610114R00-029-G |  | RES,49.9KOhm,+/-1%,1/16W,G,SMD0402 | VISHAY ENTER TECHNO LOGY.INC | CRCW040249K9FKED |  | G |  |  |  |  |  |  |  |
|  |  |  |  |  | 325 | 610114R00-011-G |  | RES,49.9KOhm,+/-1%,1/16W,G,SMD0402 | YAGEO CORPORATION COMPONENT | RC0402FR-0749K9L |  | G |  |  |  |  |  |  |  |
|  |  |  |  |  | 325 | 610114R00-044-G |  | RES,49.9KOhm,+/-1%,1/16W,G,SMD0402 | TA-I TECHNOLOGY CO., LTD. | RM04FTN4992 |  | G |  |  |  |  |  |  |  |
| Multi | N | ND | Y(4) | 326 | 326 | 610115W00-017-G |  | RES,18KOhm,+/-1%,1/16W,G,SMD0402 | KOA SPEER ELECTRONICS, INC. | RK73H1ETTP1802F | 1 | G | R1027 |  |  |  |  |  |  |
|  |  |  |  |  | 326 | 610115W00-024-G |  | RES,18KOhm,+/-1%,1/16W,G,SMD0402 | PANASONIC INDUSTRIAL CO.,LTD. | ERJ2RKF1802X |  | G |  |  |  |  |  |  |  |
|  |  |  |  |  | 326 | 610115W00-011-G |  | RES,18KOhm,+/-1%,1/16W,G,SMD0402 | YAGEO CORPORATION COMPONENT | RC0402FR-0718KL |  | G |  |  |  |  |  |  |  |
|  |  |  |  |  | 326 | 610115W00-044-G |  | RES,18KOhm,+/-1%,1/16W,G,SMD0402 | TA-I TECHNOLOGY CO., LTD. | RM04FTN1802 |  | G |  |  |  |  |  |  |  |
| Multi | ND |  | Y(4) | 327 | 327 | 61011GN00-017-G |  | RES,1.6KOhm,+/-1%,1/16W,G,SMD0402 | KOA SPEER ELECTRONICS, INC. | RK73H1ETTP1601F | 3 | G | R1089,R1460,R1462 |  |  |  |  |  |  |
|  |  |  |  |  | 327 | 61011GN00-011-G |  | RES,1.6KOhm,+/-1%,1/16W,G,SMD0402 | YAGEO CORPORATION COMPONENT | RC0402FR-071K6L |  | G |  |  |  |  |  |  |  |
|  |  |  |  |  | 327 | 61011GN00-044-G |  | RES,1.6KOhm,+/-1%,1/16W,G,SMD0402 | TA-I TECHNOLOGY CO., LTD. | RM04FTN1601 |  | G |  |  |  |  |  |  |  |
| Multi | ND | ND | Y(4) | 328 | 328 | 610118400-017-G |  | RES,27 Ohm,+/-1%,1/16W,G,SMD0402 | KOA SPEER ELECTRONICS, INC. | RK73H1ETTP27R0F | 12 | G | R1091,R1094,R1095,R1096,R1097,R1098,R1102,R1104,R1105,R1106,R1108,R1109 |  |  |  |  |  |  |
|  |  |  |  |  | 328 | 610118400-011-G |  | RES,27 Ohm,+/-1%,1/16W,G,SMD0402 | YAGEO CORPORATION COMPONENT | RC0402FR-0727RL |  | G |  |  |  |  |  |  |  |
|  |  |  |  |  | 328 | 610118400-044-G |  | RES,27 Ohm,+/-1%,1/16W,G,SMD0402 | TA-I TECHNOLOGY CO., LTD. | RM04FTN27R0 |  | G |  |  |  |  |  |  |  |
| Multi | N |  | Y(5) | 329 | 329 | 61100QH00-017-G |  | RES,510 Ohm,+/-0.1%,1/16W,G,SMD0402 | KOA SPEER ELECTRONICS, INC. | RN731ETTP5100B25 | 2 | G | R1092,R1115 |  |  |  |  |  |  |
|  |  |  |  |  | 329 | 61100QH00-011-G |  | RES,510 Ohm,+/-0.1%,1/16W,G,SMD0402 | YAGEO CORPORATION COMPONENT | RT0402BRD07510RL |  | G |  |  |  |  |  |  |  |
| Multi | ND | ND | Y(4) | 330 | 330 | 610112800-017-G |  | RES,6.04KOhm,+/-1%,1/16W,G,SMD0402 | KOA SPEER ELECTRONICS, INC. | RK73H1ETTP6041F | 1 | G | R1147 |  |  |  |  |  |  |
|  |  |  |  |  | 330 | 610112800-029-G |  | RES,6.04KOhm,+/-1%,1/16W,G,SMD0402 | VISHAY ENTER TECHNO LOGY.INC | CRCW04026K04FKED |  | G |  |  |  |  |  |  |  |
|  |  |  |  |  | 330 | 610112800-011-G |  | RES,6.04KOhm,+/-1%,1/16W,G,SMD0402 | YAGEO CORPORATION COMPONENT | RC0402FR-076K04L |  | G |  |  |  |  |  |  |  |
|  |  |  |  |  | 330 | 610112800-044-G |  | RES,6.04KOhm,+/-1%,1/16W,G,SMD0402 | TA-I TECHNOLOGY CO., LTD. | RM04FTN6041 |  | G |  |  |  |  |  |  |  |
| Multi | N | ND | Y(4) | 331 | 331 | 610103300-017-G |  | RES,100KOhm,+/-5%,1/16W,G,SMD0402 | KOA SPEER ELECTRONICS, INC. | RK73B1ETTP104J | 6 | G | R1251,R1252,R1253,R1254,R1395,R1398 |  |  |  |  |  |  |
|  |  |  |  |  | 331 | 610103300-029-G |  | RES,100KOhm,+/-5%,1/16W,G,SMD0402 | VISHAY ENTER TECHNO LOGY.INC | CRCW0402100KJNED |  | G |  |  |  |  |  |  |  |
|  |  |  |  |  | 331 | 610103300-011-G |  | RES,100KOhm,+/-5%,1/16W,G,SMD0402 | YAGEO CORPORATION COMPONENT | RC0402JR-07100KL |  | G |  |  |  |  |  |  |  |
|  |  |  |  |  | 331 | 610103300-044-G |  | RES,100KOhm,+/-5%,1/16W,G,SMD0402 | TA-I TECHNOLOGY CO., LTD. | RM04JTN104 |  | G |  |  |  |  |  |  |  |
| Multi | N | ND | Y(5) | 332 | 332 | 61100FR00-017-G |  | RES,13KOhm,+/-1%,1/16W,G,SMD0402 | KOA SPEER ELECTRONICS, INC. | RN731ETTP1302F25 | 1 | G | R1255 |  |  |  |  |  |  |
|  |  |  |  |  | 332 | 61100FR00-044-G |  | RES,13KOhm,+/-1%,1/16W,G,SMD0402 | TA-I TECHNOLOGY CO., LTD. | RB04FTP1302 |  | G |  |  |  |  |  |  |  |
| Multi | ND | ND | Y(5) | 333 | 333 | 61100BK00-017-G |  | RES,47KOhm,+/-1%,1/16W,G,SMD0402 | KOA SPEER ELECTRONICS, INC. | RN731ETTP4702F25 | 1 | G | R1262 |  |  |  |  |  |  |
|  |  |  |  |  | 333 | 61100BK00-011-G |  | RES,47KOhm,+/-1%,1/16W,G,SMD0402 | YAGEO CORPORATION COMPONENT | RT0402FRD0747KL |  | G |  |  |  |  |  |  |  |
|  |  |  |  |  | 333 | 61100BK00-044-G |  | RES,47KOhm,+/-1%,1/16W,G,SMD0402 | TA-I TECHNOLOGY CO., LTD. | RB04FTP4702 |  | G |  |  |  |  |  |  |  |
| Multi | N | ND | Y(4) | 334 | 334 | 610112N00-017-G |  | RES,130 Ohm,+/-1%,1/16W,G,SMD0402 | KOA SPEER ELECTRONICS, INC. | RK73H1ETTP1300F | 1 | G | R1280 |  |  |  |  |  |  |
|  |  |  |  |  | 334 | 610112N00-029-G |  | RES,130 Ohm,+/-1%,1/16W,G,SMD0402 | VISHAY ENTER TECHNO LOGY.INC | CRCW0402130RFKED |  | G |  |  |  |  |  |  |  |
|  |  |  |  |  | 334 | 610112N00-024-G |  | RES,130 Ohm,+/-1%,1/16W,G,SMD0402 | PANASONIC INDUSTRIAL CO.,LTD. | ERJ2RKF1300X |  | G |  |  |  |  |  |  |  |
|  |  |  |  |  | 334 | 610112N00-011-G |  | RES,130 Ohm,+/-1%,1/16W,G,SMD0402 | YAGEO CORPORATION COMPONENT | RC0402FR-07130RL |  | G |  |  |  |  |  |  |  |
|  |  |  |  |  | 334 | 610112N00-044-G |  | RES,130 Ohm,+/-1%,1/16W,G,SMD0402 | TA-I TECHNOLOGY CO., LTD. | RM04FTN1300 |  | G |  |  |  |  |  |  |  |
| Multi | ND |  | Y(4) | 335 | 335 | 61011CB00-017-G |  | RES,64.9 Ohm,+/-1%,1/16W,G,SMD0402 | KOA SPEER ELECTRONICS, INC. | RK73H1ETTP64R9F | 1 | G | R1288 |  |  |  |  |  |  |
|  |  |  |  |  | 335 | 61011CB00-011-G |  | RES,64.9 Ohm,+/-1%,1/16W,G,SMD0402 | YAGEO CORPORATION COMPONENT | RC0402FR-0764R9L |  | G |  |  |  |  |  |  |  |
|  |  |  |  |  | 335 | 61011CB00-044-G |  | RES,64.9 Ohm,+/-1%,1/16W,G,SMD0402 | TA-I TECHNOLOGY CO., LTD. | RM04FTN64R9 |  | G |  |  |  |  |  |  |  |
| Multi | N | other | Y(4) | 336 | 336 | 61010AC00-017-G |  | RES,2.2 Ohm,+/-1%,1/10W,G,SMD0603 | KOA SPEER ELECTRONICS, INC. | RK73H1JTTD2R20F | 1 | G | R1298 |  |  |  |  |  |  |
|  |  |  |  |  | 336 | 61010AC00-024-G |  | RES,2.2 Ohm,+/-1%,1/10W,G,SMD0603 | PANASONIC INDUSTRIAL CO.,LTD. | ERJ3RQF2R2V |  | G |  |  |  |  |  |  |  |
|  |  |  |  |  | 336 | 61010AC00-011-G |  | RES,2.2 Ohm,+/-1%,1/10W,G,SMD0603 | YAGEO CORPORATION COMPONENT | RC0603FR-072R2L |  | G |  |  |  |  |  |  |  |
|  |  |  |  |  | 336 | 61010AC00-044-G |  | RES,2.2 Ohm,+/-1%,1/10W,G,SMD0603 | TA-I TECHNOLOGY CO., LTD. | RM06FTN2R20 |  | G |  |  |  |  |  |  |  |
| Multi | ND | ND | Y(5) | 337 | 337 | 61100AH00-017-G |  | RES,10KOhm,+/-0.5%,1/16W,G,SMD0402 | KOA SPEER ELECTRONICS, INC. | RN731ETTP1002D25 | 8 | G | R1303,R1304,R1305,R1308,R1310,R1311,R1312,R1313 |  |  |  |  |  |  |
|  |  |  |  |  | 337 | 61100AH00-011-G |  | RES,10KOhm,+/-0.5%,1/16W,G,SMD0402 | YAGEO CORPORATION COMPONENT | RT0402DRE0710KL |  | G |  |  |  |  |  |  |  |
|  |  |  |  |  | 337 | 61100AH00-044-G |  | RES,10KOhm,+/-0.5%,1/16W,G,SMD0402 | TA-I TECHNOLOGY CO., LTD. | RB04DTP1002 |  | G |  |  |  |  |  |  |  |
| Multi | ND | ND | Y(4) | 338 | 338 | 610115N00-017-G |  | RES,2.4KOhm,+/-1%,1/16W,G,SMD0402 | KOA SPEER ELECTRONICS, INC. | RK73H1ETTP2401F | 2 | G | R1331,R1332 |  |  |  |  |  |  |
|  |  |  |  |  | 338 | 610115N00-011-G |  | RES,2.4KOhm,+/-1%,1/16W,G,SMD0402 | YAGEO CORPORATION COMPONENT | RC0402FR-072K4L |  | G |  |  |  |  |  |  |  |
|  |  |  |  |  | 338 | 610115N00-044-G |  | RES,2.4KOhm,+/-1%,1/16W,G,SMD0402 | TA-I TECHNOLOGY CO., LTD. | RM04FTN2401 |  | G |  |  |  |  |  |  |  |
| Multi | N | Other | Y(4) | 339 | 339 | 61011BW00-017-G |  | RES,1.2KOhm,+/-1%,1/16W,G,SMD0402 | KOA SPEER ELECTRONICS, INC. | RK73H1ETTP1201F | 2 | G | R1393,R1394 |  |  |  |  |  |  |
|  |  |  |  |  | 339 | 61011BW00-011-G |  | RES,1.2KOhm,+/-1%,1/16W,G,SMD0402 | YAGEO CORPORATION COMPONENT | RC0402FR-071K2L |  | G |  |  |  |  |  |  |  |
|  |  |  |  |  | 339 | 61011BW00-044-G |  | RES,1.2KOhm,+/-1%,1/16W,G,SMD0402 | TA-I TECHNOLOGY CO., LTD. | RM04FTN1201 |  | G |  |  |  |  |  |  |  |
| Multi | ND | ND | Y(4) | 340 | 340 | 61012LR00-017-G |  | RES,1KOhm,+/-0.5%,1/16W,G,SMD0402 | KOA SPEER ELECTRONICS, INC. | RK73H1ETTP1001D | 1 | G | R1480 |  |  |  |  |  |  |
|  |  |  |  |  | 340 | 61012LR00-011-G |  | RES,1KOhm,+/-0.5%,1/16W,G,SMD0402 | YAGEO CORPORATION COMPONENT | RC0402DR-071KL |  | G |  |  |  |  |  |  |  |
|  |  |  |  |  | 340 | 61012LR00-044-G |  | RES,1KOhm,+/-0.5%,1/16W,G,SMD0402 | TA-I TECHNOLOGY CO., LTD. | RM04DTN1001 |  | G |  |  |  |  |  |  |  |
| Multi | ND | ND | N | 341 | 341 | 61100QT01-017-G |  | RES,10 Ohm,+/-0.5%,1/16W,G,SMD0402 | KOA SPEER ELECTRONICS, INC. | RN731ETTP10R0D25 | 1 | G | R1483 |  |  |  |  |  |  |
|  |  |  |  |  | 341 | 61013WA00-011-G |  | RES,thick film,10Ohm,+/-0.5%,1/16W,SMD0402,G | YAGEO CORPORATION COMPONENT | RC0402DR-0710RL |  | G |  |  |  |  |  |  |  |
|  |  |  |  |  | 341 | 61013WA00-044-G |  | RES,thick film,10Ohm,+/-0.5%,1/16W,SMD0402,G | TA-I TECHNOLOGY CO., LTD. | RM04DTN10R0 |  | G |  |  |  |  |  |  |  |
| Multi | N |  | Y(5) | 342 | 342 | 61100LQ00-017-G |  | RES,20KOhm,+/-1%,1/16W,G,SMD0402 | KOA SPEER ELECTRONICS, INC. | RN731ETTP2002F50 | 1 | G | R1488 |  |  |  |  |  |  |
|  |  |  |  |  | 342 | 61100LQ00-011-G |  | RES,20KOhm,+/-1%,1/16W,G,SMD0402 | YAGEO CORPORATION COMPONENT | RT0402FRE0720KL |  | G |  |  |  |  |  |  |  |
|  |  |  |  |  | 342 | 61100LQ00-044-G |  | RES,20KOhm,+/-1%,1/16W,G,SMD0402 | TA-I TECHNOLOGY CO., LTD. | RB04FTS2002 |  | G |  |  |  |  |  |  |  |
| Multi |  |  | Y(4) | 343 | 343 | 610118800-017-G |  | RES,499KOhm,+/-1%,1/8W,G,SMD0805 | KOA SPEER ELECTRONICS, INC. | RK73H2ATTD4993F | 1 | G | R1492 |  |  |  |  |  |  |
|  |  |  |  |  | 343 | 610118800-024-G |  | RES,499KOhm,+/-1%,1/8W,G,SMD0805 | PANASONIC INDUSTRIAL CO.,LTD. | ERJ6ENF4993V |  | G |  |  |  |  |  |  |  |
|  |  |  |  |  | 343 | 610118800-011-G |  | RES,499KOhm,+/-1%,1/8W,G,SMD0805 | YAGEO CORPORATION COMPONENT | RC0805FR-07499KL |  | G |  |  |  |  |  |  |  |
| Multi | ND | ND | Y(4) | 344 | 344 | 61011LF00-017-G |  | RES,499KOhm,+/-1%,1/16W,G,SMD0402 | KOA SPEER ELECTRONICS, INC. | RK73H1ETTP4993F | 2 | G | R1493,R1847 |  |  |  |  |  |  |
|  |  |  |  |  | 344 | 61011LF00-024-G |  | RES,499KOhm,+/-1%,1/16W,G,SMD0402 | PANASONIC INDUSTRIAL CO.,LTD. | ERJ2RKF4993X |  | G |  |  |  |  |  |  |  |
|  |  |  |  |  | 344 | 61011LF00-011-G |  | RES,499KOhm,+/-1%,1/16W,G,SMD0402 | YAGEO CORPORATION COMPONENT | RC0402FR-07499KL |  | G |  |  |  |  |  |  |  |
|  |  |  |  |  | 344 | 61011LF00-044-G |  | RES,499KOhm,+/-1%,1/16W,G,SMD0402 | TA-I TECHNOLOGY CO., LTD. | RM04FTN4993 |  | G |  |  |  |  |  |  |  |
| Multi | ND | ND | Y(4) | 345 | 345 | 61011HC00-017-G |  | RES,2.7KOhm,+/-1%,1/16W,G,SMD0402 | KOA SPEER ELECTRONICS, INC. | RK73H1ETTP2701F | 1 | G | R1754 |  |  |  |  |  |  |
|  |  |  |  |  | 345 | 61011HC00-029-G |  | RES,2.7KOhm,+/-1%,1/16W,G,SMD0402 | VISHAY ENTER TECHNO LOGY.INC | CRCW04022K70FKED |  | G |  |  |  |  |  |  |  |
|  |  |  |  |  | 345 | 61011HC00-024-G |  | RES,2.7KOhm,+/-1%,1/16W,G,SMD0402 | PANASONIC INDUSTRIAL CO.,LTD. | ERJ2RKF2701X |  | G |  |  |  |  |  |  |  |
|  |  |  |  |  | 345 | 61011HC00-011-G |  | RES,2.7KOhm,+/-1%,1/16W,G,SMD0402 | YAGEO CORPORATION COMPONENT | RC0402FR-072K7L |  | G |  |  |  |  |  |  |  |
|  |  |  |  |  | 345 | 61011HC00-044-G |  | RES,2.7KOhm,+/-1%,1/16W,G,SMD0402 | TA-I TECHNOLOGY CO., LTD. | RM04FTN2701 |  | G |  |  |  |  |  |  |  |
| Multi | ND | ND | Y(4) | 346 | 346 | 61010KR00-017-G |  | RES,4.99 Ohm,+/-1%,1/10W,G,SMD0603 | KOA SPEER ELECTRONICS, INC. | RK73H1JTTD4R99F | 1 | G | R1756 |  |  |  |  |  |  |
|  |  |  |  |  | 346 | 61015JL00-029-G |  | RES,4.99 Ohm,+/-1%,1/4W,G,SMD0603 | VISHAY ENTER TECHNO LOGY.INC | CRCW06034R99FKEA |  | G |  |  |  |  |  |  |  |
|  |  |  |  |  | 346 | 61010KR00-011-G |  | RES,4.99 Ohm,+/-1%,1/10W,G,SMD0603 | YAGEO CORPORATION COMPONENT | RC0603FR-074R99L |  | G |  |  |  |  |  |  |  |
| Multi | ND |  | Y(4) | 347 | 347 | 610130300-017-G |  | RES,60.4 Ohm,+/-1%,1/20W,G,SMD0201 | KOA SPEER ELECTRONICS, INC. | RK73H1HTTC60R4F | 2 | G | R1769,R1770 |  |  |  |  |  |  |
|  |  |  |  |  | 347 | 610130300-024-G |  | RES,60.4 Ohm,+/-1%,1/20W,G,SMD0201 | PANASONIC INDUSTRIAL CO.,LTD. | ERJ1GNF60R4C |  | G |  |  |  |  |  |  |  |
|  |  |  |  |  | 347 | 610130300-029-G |  | RES,60.4 Ohm,+/-1%,1/20W,G,SMD0201 | VISHAY ENTER TECHNO LOGY.INC | CRCW020160R4FKED |  | G |  |  |  |  |  |  |  |
|  |  |  |  |  | 347 | 610130300-011-G |  | RES,60.4 Ohm,+/-1%,1/20W,G,SMD0201 | YAGEO CORPORATION COMPONENT | RC0201FR-0760R4L |  | G |  |  |  |  |  |  |  |
| Multi | ND |  | N | 348 | 348 | 31050KS00-185-G |  | IC,Buffer,NC7SV17P5X,0.9V~3.6V,G,SC70-5,SMD | FAIRCHILD SEMICONDUCTOR CORP | NC7SV17P5X | 2 | G | U2,U11 |  |  |  |  |  |  |
|  |  |  |  |  | 348 | 310507P00-031-G |  | Logic IC,Buffer,74AUP1G17GW,0.8V~3.6V,19ns,TSSOP,5P,G | NXP SEMICONDUCTORS | 74AUP1G17GW |  | G |  |  |  |  |  |  |  |
| Multi | ND |  | Y(1) | 349 | 349 | 320242G00-183-G |  | IC,Power Controller,LM3880MFX-1AA/NOPB,G,SOT-23-6,SMD | TEXAS INSTRUMENTS | LM3880MFX-1AA/NOPB | 2 | G | U3,U4 |  |  |  |  |  |  |
|  |  |  |  |  | 349 | 32024HB00-183-G |  | IC,Power Controller,LM3880MF-1AA/NOPB,G,SOT-23-6,SMD | TEXAS INSTRUMENTS | LM3880MF-1AA/NOPB |  | G |  |  |  |  |  |  |  |
| Multi | ND | ND | Y(3) | 350 | 350 | 310502800-031-G |  | IC,Buffer,74LVC1G07GW,1.65~5.5V,G,SOT353-5,SMD | NXP SEMICONDUCTORS | 74LVC1G07GW | 25 | G | U6,U7,U8,U9,U53,U54,U56,U57,U58,U59,U64,U65,U67,U69,U70,U71,U72,U85,U88,U111,U113,U114,U115,U117,U169 |  |  |  |  |  |  |
|  |  |  |  |  | 350 | 310502C00-223-G |  | IC,Buffer,NL17SZ07DFT2G,1.65~5.50V,G,SC-88A/SOT-353-5,SMD | ON SEMICONDUCTOR CORP | NL17SZ07DFT2G |  | G |  |  |  |  |  |  |  |
|  |  |  |  |  | 350 | 31050CU00-131-G |  | IC,Buffer,TC7SZ07FU,1.65~5.5V,G,SSOP-5,SMD | TOSHIBA ELECTRONICS ASIA LTD | TC7SZ07FU |  | G |  |  |  |  |  |  |  |
| Sole | Y | ND | Y(1) | 351 | 351 | 21040M500-283-G |  | IC,BROADCOM,BCM54612EB1KMLG,B1,G,MLP-48,SMD | BROADCOM SINGAPORE PTE LTD. | BCM54612EB1KMLG | 1 | G | U13 |  |  |  |  |  |  |
| Sole | ND |  | N | 352 | 352 | 21012NH00-687-G |  | IC,ASPEED,AST2500A2-GP,A2,G,TFBGA-456,SMD | ASPEED TECHNOLOGY INC | AST2520A2-GP | 1 | G | U14 |  |  |  |  |  |  |
| Multi | ND | ND | Y(2) | 353 | 353 | 31030CA00-031-G |  | IC,Switch,PCA9546APW,2.3~5.5V,G,TSSOP-16,SMD | NXP SEMICONDUCTORS | PCA9546APW | 2 | G | U15,U16 |  |  |  |  |  |  |
|  |  |  |  |  | 353 | 31030YF00-252-G |  | Logic IC,Switch,PI4MSD5V9546ALEX,1.65V~5.5V,0.3ns,TSSOP,16P,G | PERICOM SEMICONDUCTOR CORP | PI4MSD5V9546ALEX |  | G |  |  |  |  |  |  |  |
| Multi | ND |  | Y(1) | 354 | 354 | 420212A00-216-G |  | DRAM,MT40A512M16JY-083E:B,1.2V,512M*16,1.2GHz,G,FBGA-96,SMD | MICRON SEMICONDUCTOR ASIA PTE.LTD. | MT40A512M16JY-083E:B | 1 | G | U17 |  |  |  |  |  |  |
|  |  |  |  |  | 354 | 420214J00-220-G |  | DRAM,H5AN8G6NAFR-UHC,1.2V,8G,1.2GHz,G,FBGA-96,SMD | HYNIX SEMICONDUCTOR INC | H5AN8G6NAFR-UHC |  | G |  |  |  |  |  |  |  |
| Sole | N |  | Y(1) | 355 | 355 | 310311G00-183-G |  | IC,Switch,TS3L110RGYR,3V~3.6V,G,VQFN-16,SMD | TEXAS INSTRUMENTS | TS3L110RGYR | 2 | G | U18,U19 |  |  |  |  |  |  |
| Multi | ND | ND | N | 356 | 356 | 41050DL00-233-G |  | Flash,MX25L6445EMI-10G,2.7~3.6V,64M,SPI,G,SOP-16,SMD | MACRONIX INTERNATIONAL CO.,LTD. | MX25L6445EMI-10G | 1 | G | U24 |  |  |  |  |  |  |
|  |  |  |  |  | 356 | 41050SF00-233-G |  | Flash,MX25L6435EMI-10G,2.7~3.6V,64M,SPI,G,SOP-16,SMD | MACRONIX INTERNATIONAL CO.,LTD. | MX25L6435EMI-10G |  | G |  |  |  |  |  |  |  |
|  |  |  |  |  | 356 | MX25L6433FMI-08G |  | Flash,MX25L6433FMI-08G,2.7~3.6V,64M,SPI,G,SOP-16,SMD | MACRONIX INTERNATIONAL CO.,LTD. | MX25L6433FMI-08G |  | G |  |  |  |  |  |  |  |
| Multi | ND |  | N | 357 | 357 | 310312S00-217-G |  | IC,Switch,74CBTLV3125QG8,2.3V~3.6V,G,QSOP-16,SMD | INTEGRATED DEVICE TECHNOLOGY | 74CBTLV3125QG8 | 2 | G | U25,U179 |  |  |  |  |  |  |
|  |  |  |  |  | 357 | 310305U00-252-G |  | Logic IC,Switch,PI3B3125QEX,3.0V~3.6V,0.25ns,QSOP,16P,G | PERICOM SEMICONDUCTOR CORP | PI3B3125QEX |  | G |  |  |  |  |  |  |  |
| Multi | ND | ND | N | 358 | 358 | 310408900-217-G |  | IC,Switch,74CBTLV3257PGG8,2.3~3.6V,G,TSSOP-16,SMD | INTEGRATED DEVICE TECHNOLOGY | 74CBTLV3257PGG8 | 1 | G | U27 |  |  |  |  |  |  |
|  |  |  |  |  | 358 | 310405F00-252-G |  | Logic IC,Multiplexer,PI3B3257LEX,2.97V~3.63V,0.25ns,TSSOP,16P,G | PERICOM SEMICONDUCTOR CORP | PI3B3257LEX |  | G |  |  |  |  |  |  |  |
| Multi | N | ND | Y(1) | 359 | 359 | 21050F900-217-G |  | IC,IDT,2305B-1DCG8,B,G,SOIC-8,SMD | INTEGRATED DEVICE TECHNOLOGY | 2305B-1DCG8 | 1 | G | U29 |  |  |  |  |  |  |
|  |  |  |  |  | 359 | 31050JC00-223-G |  | Logic IC,Buffer,NB2305AI1DR2G,3.0V~3.6V,0.35ns,SOIC,8P,G | ON SEMICONDUCTOR CORP | NB2305AI1DR2G |  | G |  |  |  |  |  |  |  |
| Multi | N | 1 | Y(3) | 360 | 360 | 41040BT00-191-G |  | EEPROM,AT24C64D-SSHM-T,1.7~5.5V,64K,I2C,G,SOIC-8,SMD | ATMEL CORPORATION | AT24C64D-SSHM-T | 1 | G | U30 |  |  |  |  |  |  |
|  |  |  |  |  | 360 | 410405H00-214-G |  | EEPROM,M24C64-RMN6TP,1.8~5.5V,64K,I2C,G,SO-8,SMD | ST MICRO ELECTRONICS,INC | M24C64-RMN6TP |  | G |  |  |  |  |  |  |  |
|  |  |  |  |  | 360 | 410409E00-223-G |  | EEPROM,CAT24C64WI-GT3,1.8~5.5V,64K,I2C,G,SOIC-8,SMD | ON SEMICONDUCTOR CORP | CAT24C64WI-GT3 |  | G |  |  |  |  |  |  |  |
| Multi | N | 1 | N | 361 | 361 | 320501P00-173-G |  | IC,Driver/Receiver,MAX3243CAI+T,G,SSOP-28,SMD | MAXIM INTEGRATED PRODUCTS, INC. | MAX3243CAI+T | 1 | G | U32 |  |  |  |  |  |  |
|  |  |  |  |  | 361 | 320503B00-214-G |  | IC,Driver/Receiver,ST3243ECTR-E,G,TSSOP-28,SMD | ST MICRO ELECTRONICS,INC | ST3243ECTR-E |  | G |  |  |  |  |  |  |  |
| Sole | ND | ND | N | 362 | 362 | 32022AL00-223-G |  | IC,Power Controller,NCP380HSNAJAAT1G,G,TSOP-6,SMD | ON SEMICONDUCTOR CORP | NCP380HSNAJAAT1G | 3 | G | U33,U35,U177 |  |  |  |  |  |  |
| Sole | ND |  | N | 363 | 363 | 21081AQ00-426-G |  | IC,RENESAS,uPD720201K8-701-BAC-A,G,QFN-68,SMD | RENESAS TECHNOLOGY AMERICA INC | uPD720201K8-701-BAC-A | 1 | G | U36 |  |  |  |  |  |  |
| Sole | ND | ND | N | 364 | 364 | 41050J100-233-G |  | Flash,MX25L5121EMC-20G,2.7~3.6V,512K,SPI,G,SOP-8,SMD | MACRONIX INTERNATIONAL CO.,LTD. | MX25L5121EMC-20G | 1 | G | U37 |  |  |  |  |  |  |
| Sole | ND |  | N | 365 | 365 | 210826400-183-G |  | IC,TI,TUSB2077APTR,G,LQFP-48,SMD | TEXAS INSTRUMENTS | TUSB2077APTR | 1 | G | U38 |  |  |  |  |  |  |
| Sole | ND |  | N | 366 | 366 | 21081N000-348-G |  | IC,MARVELL,88SE9235A1-NAA2C000,A1,G,QFN-76,SMD | MARVELL SEMICONDUCTOR, INC | 88SE9235A1-NAA2C000[VER.A1] | 1 | G | U45 |  |  |  |  |  |  |
| Multi | ND | ND | N | 367 | 367 | 41050K700-233-G |  | Flash,MX25L4006EM2I-12G,2.7V~3.6V,4M,SPI,G,SOP-8,SMD | MACRONIX INTERNATIONAL CO.,LTD. | MX25L4006EM2I-12G | 1 | G | U46 |  |  |  |  |  |  |
|  |  |  |  |  | 367 | 41050RL00-205-G |  | NOR Flash,W25X40CLSSIG,2.3V,N/A,3.6V,4M,SPI,-40_x0003_~85_x0003_,SOIC,8P,G | WINBOND ELECTRONIC CO.,LTD. | W25X40CLSSIG |  | G |  |  |  |  |  |  |  |
| Multi | ND | ND | Y(3) | 368 | 368 | 310203000-031-G |  | IC,Trigger,74LVC74APW,1.2~3.6V,G,TSSOP-14,SMD | NXP SEMICONDUCTORS | 74LVC74APW | 2 | G | U55,U168 |  |  |  |  |  |  |
|  |  |  |  |  | 368 | 310202400-223-G |  | IC,Trigger,MC74LCX74DTR2G,2.3~3.6V,G,TSSOP-14,SMD | ON SEMICONDUCTOR CORP | MC74LCX74DTR2G |  | G |  |  |  |  |  |  |  |
|  |  |  |  |  | 368 | 310208S00-131-G |  | IC,Trigger,74LCX74FT,1.65V~3.6V,G,TSSOP-14,SMD | TOSHIBA ELECTRONICS ASIA LTD | 74LCX74FT |  | G |  |  |  |  |  |  |  |
| Sole | Y |  | N | 369 | 369 | 21050P200-031-G |  | IC,NXP,PCF8523TK,G,HVSON-8,SMD | NXP SEMICONDUCTORS | PCF8523TK | 1 | G | U60 |  |  |  |  |  |  |
| Multi | ND |  | N | 370 | 370 | 21050Q600-217-G |  | IC,IDT,5PB1102PGGI8,G,TSSOP-8,SMD | INTEGRATED DEVICE TECHNOLOGY | 5PB1102PGGI8 | 1 | G | U61 |  |  |  |  |  |  |
|  |  |  |  |  | 370 | 31050JY00-223-G |  | Logic IC,Buffer,NB3V1102CDTR2G,1.8V/2.5V/3.3V,3.5ns,TSSOP,8P,G | ON SEMICONDUCTOR CORP | NB3V1102CDTR2G |  | G |  |  |  |  |  |  |  |
| Sole | ND | ND | N | 371 | 371 | 21050R500-298-G |  | IC,SILABS,Si5338C-B06799-GMR,G,QFN-24,SMD | Silicon Laboratories Inc. | SI5338C-B06799-GMR | 1 | G | U62 |  |  |  |  |  |  |
| Sole | ND |  | Y(1) | 372 | 372 | 21050P100-217-G |  | IC,IDT,9DBL0452BKILFT,G,VFQFPN-32,SMD | INTEGRATED DEVICE TECHNOLOGY | 9DBL0452BKILFT | 1 | G | U63 |  |  |  |  |  |  |
| Multi | N | ND | Y(3) | 373 | 373 | 310101400-031-G |  | IC,Gate&Inverter,74LVC1G08GW,1.65~5.5V,G,SOT353-5,SMD | NXP SEMICONDUCTORS | 74LVC1G08GW | 13 | G | U66,U73,U74,U75,U76,U77,U78,U79,U80,U81,U82,U161,U178 |  |  |  |  |  |  |
|  |  |  |  |  | 373 | 310103J00-223-G |  | IC,Gate&Inverter,NL17SZ08DFT2G,1.65~5.5V,G,SOT353-5,SMD | ON SEMICONDUCTOR CORP | NL17SZ08DFT2G |  | G |  |  |  |  |  |  |  |
|  |  |  |  |  | 373 | 31010J400-131-G |  | IC,Gate&Inverter,TC7SZ08FU,1.8~5.5V,G,SSOP-5,SMD | TOSHIBA ELECTRONICS ASIA LTD | TC7SZ08FU |  | G |  |  |  |  |  |  |  |
| Multi | ND |  | N | 374 | 374 | 310504B00-031-G |  | IC,Buffer,74LVC1G17GW,1.65~5.5V,G,SOT353-5,SMD | NXP SEMICONDUCTORS | 74LVC1G17GW | 3 | G | U68,U86,U89 |  |  |  |  |  |  |
|  |  |  |  |  | 374 | 310507Q00-223-G |  | Logic IC,Buffer,NL17SZ17DFT2G,1.65V~5.5V,15ns,SC-88A/SOT-353,5P,G | ON SEMICONDUCTOR CORP | NL17SZ17DFT2G |  | G |  |  |  |  |  |  |  |
|  |  |  |  |  | 374 | 31050BH00-131-G |  | IC,Buffer,TC7SZ17FU,1.65~5.5V,G,SSOP-5,SMD | TOSHIBA ELECTRONICS ASIA LTD | TC7SZ17FU |  | G |  |  |  |  |  |  |  |
| Multi | ND | ND | Y(3) | 375 | 375 | 310500F00-031-G |  | IC,Buffer,74LVC07APW,1.65~5.5V,G,TSSOP-14,SMD | NXP SEMICONDUCTORS | 74LVC07APW | 3 | G | U83,U101,U102 |  |  |  |  |  |  |
|  |  |  |  |  | 375 | 31050LF00-237-G |  | IC,Buffer,74LVC07AT14-13,1.65V~5.5V,G,TSSOP-14,SMD | DIODES INCORPORATION | 74LVC07AT14-13 |  | G |  |  |  |  |  |  |  |
| Sole | ND |  | Y(1) | 376 | 376 | 320231500-183-G |  | IC,Voltage Sensor,TPS3897ADRYR,G,SON-6,SMD | TEXAS INSTRUMENTS | TPS3897ADRYR | 1 | G | U84 |  |  |  |  |  |  |
| Sole | ND |  | Y(1) | 377 | 377 | 32020LS00-183-G |  | IC,Power Controller,TPS3801K33DCKR,G,SC-70-5,SMD | TEXAS INSTRUMENTS | TPS3801K33DCKR | 1 | G | U87 |  |  |  |  |  |  |
| Multi | Y | 1 | Y(3) | 378 | 378 | 310201900-031-G |  | IC,Gate&Inverter,74LVC2G14GW,1.65~5.5V,G,SOT363-6,SMD | NXP SEMICONDUCTORS | 74LVC2G14GW | 3 | G | U90,U91,U112 |  |  |  |  |  |  |
|  |  |  |  |  | 378 | 310203300-223-G |  | Logic IC,Trigger,NL27WZ14DFT2G,1.65V~5.5V,7.4ns,SC-70/SOT-323,6P,G | ON SEMICONDUCTOR CORP | NL27WZ14DFT2G |  | G |  |  |  |  |  |  |  |
| Sole | ND |  | Y(3) | 379 | 379 | 31050J800-031-G |  | IC,Buffer,PCA9516APW,2.3V~3.6V,G,TSSOP-16,SMD | NXP SEMICONDUCTORS | PCA9516APW | 4 | G | U92,U93,U94,U95 |  |  |  |  |  |  |
| Sole | N |  | Y(2) | 380 | 380 | 32021R100-252-G |  | IC,Power Controller,PI3USB102ZLEX,G,TQFN-10P,SMD | PERICOM SEMICONDUCTOR CORP | PI3USB102ZLEX | 2 | G | U96,U108 |  |  |  |  |  |  |
| Sole | ND |  | Y(2) | 381 | 381 | 31090C800-031-G |  | IC,Transceiver,74AVC4TD245GU,0.8V~3.6V,G,XQFN-16,SMD | NXP SEMICONDUCTORS | 74AVC4TD245GU | 1 | G | U97 |  |  |  |  |  |  |
| Multi | ND | ND | Y(1) | 382 | 382 | 410403P00-214-G |  | EEPROM,M24512-WMN6TP,2.5~5.5V,512K,I2C,G,SO-8,SMD | ST MICRO ELECTRONICS,INC | M24512-WMN6TP | 1 | G | U98 |  |  |  |  |  |  |
|  |  |  |  |  | 382 | 41040D200-191-G |  | EEP Memory,AT24C512C-SSHM-T,1.7V,N/A,3.6V,512K,I2C,-40_x0003_~85_x0003_,SOIC,8P,G | ATMEL CORPORATION | AT24C512C-SSHM-T |  | G |  |  |  |  |  |  |  |
|  |  |  |  |  | 382 | 410406K00-214-G |  | EEP Memory,M24512-RMN6TP,1.8V,N/A,5.5V,512K,I2C,-40_x0003_~85_x0003_,SO,8P,G | ST MICRO ELECTRONICS,INC | M24512-RMN6TP |  | G |  |  |  |  |  |  |  |
| Sole | ND | ND | Y(2) | 383 | 383 | 210203M00-031-G |  | IC,NXP,PCA9554PW,G,TSSOP-16,SMD | NXP SEMICONDUCTORS | PCA9554PW | 2 | G | U99,U100 |  |  |  |  |  |  |
| Multi | ND |  | N | 384 | 384 | 311004800-031-G |  | IC,Translator,PCA9617ADPJ,0.8~5.5V,2.2~5.5V,G,TSSOP-8,SMD | NXP SEMICONDUCTORS | PCA9617ADPJ | 4 | G | U104,U105,U106,U107 |  |  |  |  |  |  |
|  |  |  |  |  | 384 | 311004V00-223-G |  | Logic IC,Translator,PCA9617ADMR2G,Vcca=0.8V~5.5V,Vccb=2.2V~5.5V,102ns,Micro8,8P,G | ON SEMICONDUCTOR CORP | PCA9617ADMR2G |  | G |  |  |  |  |  |  |  |
| Multi | ND |  | Y(2) | 385 | 385 | 310307T00-031-G |  | IC,Switch,74CBTLV1G125GV,2.3~3.6V,G,SOT753-5,SMD | NXP SEMICONDUCTORS | 74CBTLV1G125GV | 1 | G | U109 |  |  |  |  |  |  |
|  |  |  |  |  | 385 | 310300D00-183-G |  | Logic IC,Switch,SN74CBTLV1G125DBVR,2.3V-3.6V,0.25ns,SOT-23,5P,G | Texas Instruments | SN74CBTLV1G125DBVR |  | G |  |  |  |  |  |  |  |
| Multi | ND |  | N | 386 | 386 | 330103N00-426-G |  | IC,Optocoupler,PS2811-1-F3-A,G,SSOP-4,SMD | RENESAS TECHNOLOGY AMERICA INC | PS2811-1-F3-A | 1 | G | U110 |  |  |  |  |  |  |
|  |  |  |  |  | 386 | 330102900-289-G |  | OPTO-IC,ISOL,LTV-217-G,SSOP,4P,G | LITE-ON TECHNOLOGY CORPORATION | LTV-217-G |  | G |  |  |  |  |  |  |  |
| Sole | ND |  | N | 387 | 387 | 21081WR00-031-G |  | IC,NXP,PCA9541APW/01,G,TSSOP-16,SMD | NXP SEMICONDUCTORS | PCA9541APW/01 | 1 | G | U116 |  |  |  |  |  |  |
| Sole | ND |  | Y(1) | 388 | 388 | 311006F00-031-G |  | IC,Translator,PCA9508D,0.9V~5.5V/2.7V~5.5V,G,SO-8,SMD | NXP SEMICONDUCTORS | PCA9508D | 1 | G | U164 |  |  |  |  |  |  |
| Sole | ND |  | N | 389 | 389 | 320242H00-226-G |  | IC,Power Controller,LTC2955CDDB-2#TRMPBF,G,DFN-10,SMD | LINEAR TECHNOLOGY CORPORATION | LTC2955CDDB-2#TRMPBF | 1 | G | U165 |  |  |  |  |  |  |
| Sole | ND |  | N | 390 | 390 | 32050Q900-031-G |  | IC,LED Driver,PCA9551PW,G,TSSOP-16,SMD | NXP SEMICONDUCTORS | PCA9551PW | 1 | G | U166 |  |  |  |  |  |  |
| Multi | N | Other | Y(4) | 391 | 391 | 310203U00-223-G |  | IC,Trigger,NL17SZ14DFT2G,1.65~5.5V,G,SOT353-5,SMD | ON SEMICONDUCTOR CORP | NL17SZ14DFT2G | 1 | G | U167 |  |  |  |  |  |  |
|  |  |  |  |  | 391 | 310107000-031-G |  | Logic IC,Gate&Inverter,74LVC1G14GW,1.65V~5.5V,14ns,TSSOP,5P,G | NXP SEMICONDUCTORS | 74LVC1G14GW |  | G |  |  |  |  |  |  |  |
|  |  |  |  |  | 391 | 310200900-185-G |  | IC,Trigger,NC7SZ14P5X,1.65-5.5V,G,SC70-5P,SMD | FAIRCHILD SEMICONDUCTOR CORP | NC7SZ14P5X |  | G |  |  |  |  |  |  |  |
| Multi | ND | ND | Y(3) | 392 | 392 | 310109D00-031-G |  | IC,Gate&Inverter,74LVC1G32GW,1.65~5.5V,G,TSSOP-5,SMD | NXP SEMICONDUCTORS | 74LVC1G32GW | 3 | G | U170,U174,U180 |  |  |  |  |  |  |
|  |  |  |  |  | 392 | 310109E00-223-G |  | IC,Gate&Inverter,NL17SZ32DFT2G,1.65~5.5V,G,SOT-353-5,SMD | ON SEMICONDUCTOR CORP | NL17SZ32DFT2G |  | G |  |  |  |  |  |  |  |
|  |  |  |  |  | 392 | 310108600-131-G |  | IC,Gate&Inverter,TC7SZ32FU,1.65~5.5V,G,SSOP-5,SMD | TOSHIBA ELECTRONICS ASIA LTD | TC7SZ32FU |  | G |  |  |  |  |  |  |  |
| Multi | ND |  | Y(3) | 393 | 393 | 31050KL00-031-G |  | IC,Buffer,74HC75PW,2.0V~6.0V,G,TSSOP-16,SMD | NXP SEMICONDUCTORS | 74HC75PW | 1 | G | U171 |  |  |  |  |  |  |
|  |  |  |  |  | 393 | 311007400-183-G |  | IC,Translator,CD74HC75PWRG4,2V~6V,G,TSSOP-16,SMD | Texas Instruments | CD74HC75PWRG4 |  | G |  |  |  |  |  |  |  |
| Sole | ND |  | Y(1) | 394 | 394 | 31010SB00-183-G |  | Logic IC,Gate,ISO1540DR,3V~5.5V,G,SOIC-8,SMD | TEXAS INSTRUMENTS | ISO1540DR | 1 | G | U175 |  |  |  |  |  |  |
| Multi | ND | ND | N | 395 | 395 | 71010SY00-107-G |  | XTAL,25MHz,+/-30ppm,20pF,G,SMD | DAISHINKU CORPORATION/DAISHINKU SINGAPORE PTE LTD/KDS | 1Y725000CC1G | 1 | G | X2 |  |  |  |  |  |  |
|  |  |  |  |  | 395 | 71012JL00-873-G |  | XTAL,25MHz,+/-30ppm,20pF,G,SMD-2P | KYOCERA ELCO CORPORATION | CX5032GA25000R0KDQZ1 |  | G |  |  |  |  |  |  |  |
| Multi | ND |  | N | 396 | 396 | 710113800-100-G |  | XTAL,24MHz,+/-30ppm,20pF,G,SMD | TXC CORPORATION | 7B24000038 | 1 | G | X3 |  |  |  |  |  |  |
|  |  |  |  |  | 396 | 71012JK00-873-G |  | XTAL,24MHz,+/-30ppm,20pF,G,SMD | KYOCERA ELCO CORPORATION | CX5032SB24000R0KZQ01 |  | G |  |  |  |  |  |  |  |
| Sole | ND |  | N | 397 | 397 | 71012EC00-162-G |  | XTAL,6MHz,+/-30ppm,20pF,G,SMD | EPSON ELECTRONICS AMERICA,INC. | Q22MA4061164200 | 1 | G | X4 |  |  |  |  |  |  |
| Sole | ND |  | N | 398 | 398 | 71011UL00-107-G |  | XTAL,25MHz,+/-15ppm,16pF,G,SMD | DAISHINKU CORPORATION/DAISHINKU SINGAPORE PTE LTD/KDS | 1ZHY25000BB0A | 1 | G | X5 |  |  |  |  |  |  |
| Multi | ND |  | Y(1) | 399 | 399 | 710106900-162-G |  | XTAL,32.768KHz,+/-20ppm,12.5pF,G,SMD | EPSON ELECTRONICS AMERICA,INC. | Q13FC1350000400 | 1 | G | X6 |  |  |  |  |  |  |
|  |  |  |  |  | 399 | 710110M00-873-G |  | XTAL,32.768KHz,+/-20ppm,12.5pF,G,SMD | KYOCERA ELCO CORPORATION | ST3215SB32768H5HPWAA |  | G |  |  |  |  |  |  |  |
|  |  |  |  |  | 399 | 710123400-061-G |  | XTAL,32.768KHz,+/-20ppm,12.5pF,G,SMD | TAITIEN ELECTRONICS CO.,LTD | 06172-W-052-3 |  | G |  |  |  |  |  |  |  |
| Sole | ND |  | N | 400 | 400 | 71020SC00-107-G |  | OSC,24MHz,+/-25ppm,3.3V,15pF,G,SMD | DAISHINKU CORPORATION/DAISHINKU SINGAPORE PTE LTD/KDS | 1XSE024000AR40 | 1 | G | Y1 |  |  |  |  |  |  |
| Multi | N |  | N | 401 | 401 | 71020Q600-16G-G |  | OSC,50MHz,50ppm,3.3V,G,SMD | SiTime Corporation | SIT1602AC-23-33E-50.000000T | 1 | G | Y2 |  |  |  |  |  |  |
|  |  |  |  |  | 401 | 71012DA00-100-G |  | OSC,50MHz,+/-25ppm,15pF,G,SMD | TXC CORPORATION | 7X50000015 |  | G |  |  |  |  |  |  |  |
|  |  |  |  |  | 401 | 710216Q00-098-G |  | OSC,50MHz,+/-50ppm,3.3V,15pF,G,SMD | HARMONY (HELE) | SSW050000I3CHE-ST7R2 |  | G |  |  |  |  |  |  |  |
| Sole | ND |  | N | 402 | 402 | 710213J00-16G-G |  | OSC,25MHz,+/-1.5ppm,3.3V,15pF,G,SMD | SiTime Corporation | SIT5000AC-3B-33N0-25.000000T | 1 | G | Y3 |  |  |  |  |  |  |
| Multi | ND | ND | Y(1) | 403 | 403 | 71020KL00-100-G |  | OSC,33MHz,+/-50ppm,3.3V,15pF,G,SMD | TXC CORPORATION | 7X33000013 | 1 | G | Y4 |  |  |  |  |  |  |
|  |  |  |  |  | 403 | 710211800-967-G |  | OSC,33MHz,+/-50ppm,3.3V,15pF,G,SMD | SaRonix-eCERA Corporation | FK3300011 |  | G |  |  |  |  |  |  |  |
|  |  |  |  |  | 403 | 710216N00-873-G |  | OSC,33MHz,+/-50ppm,3.3V,15pF,G,SMD | KYOCERA ELCO CORPORATION | KC3225K33.0000C10E00 |  | G |  |  |  |  |  |  |  |
| Sole | Y |  | N | 404 | 404 | 340660600-GRS-G |  | CONN,Header,Battery Holder,Bla,21.3mm,G/F,G,SMD-2 | LOTES CO LTD | AAA-BAT-063-P02_A | 1 | G | B1 |  |  |  |  |  |  |
| Sole | ND | ND | N | 405 | 405 | 2T714BY00-086-G |  | Fuse Clips,10.67mm*7.11mm*7.87mm,G,LITTELFUSE,01220088Z | LITTELFUSE FAR EAST PTE LTD | 01220088Z | 4 | G | CLIP1,CLIP2,CLIP3,CLIP4 |  |  |  |  |  |  |
| Multi | ND | ND | N | 406 | 406 | 34021BC00-G78-G |  | CONN,DDR IV,V/T,1.2V,Blu,0.85mm,15u,G,SMD-288 | FCI CONNECTORS HONGKONG LTD. | 10140702-0302K11LF | 16 | G | DIMM02,DIMM04,DIMM06,DIMM09,DIMM11,DIMM13,DIMM15,DIMM16,DIMM18,DIMM20,DIMM22,DIMM25,DIMM27,DIMM29,DIMM31,DIMM00 |  |  |  |  |  |  |
|  |  |  |  |  | 406 | 34021CD00-600-G |  | Memory Connector,AH58897-T2L31-3F,DDR IV,288,SMD,THERMOPLASTIC,0.85mm,15u",Blue,G | FOXCONN TECHNOLOGY CO.,LTD. | AH58897-T2L31-3F |  | G |  |  |  |  |  |  |  |
| Multi | ND | ND | N | 407 | 407 | 34021BD00-G78-G |  | CONN,DDR IV,V/T,1.2V,Bla,0.85mm,15u,G,SMD-288 | FCI CONNECTORS HONGKONG LTD. | 10140702-0301K11LF | 16 | G | DIMM01,DIMM03,DIMM05,DIMM07,DIMM08,DIMM10,DIMM12,DIMM14,DIMM17,DIMM19,DIMM21,DIMM23,DIMM24,DIMM26,DIMM28,DIMM30 |  |  |  |  |  |  |
|  |  |  |  |  | 407 | 34021CF00-600-G |  | Memory Connector,AH58897-T2B21-3F,DDR IV,288,SMD,THERMOPLASTIC,0.85mm,15u",Black,G | FOXCONN TECHNOLOGY CO.,LTD. | AH58897-T2B21-3F |  | G |  |  |  |  |  |  |  |
| Multi | ND | ND | N | 408 | 408 | 340612R00-309-G |  | CONN,Jumper,Bla,2.54mm,G,DIP-2 | SAMTEC INC. | SNT-100-BK-G | 4 | G | JP1(2-3),JP4(2-3),JP5(2-3),JP6(1-2) |  |  |  |  |  |  |
|  |  |  |  |  | 408 | 34065L900-GRT-G |  | CONN,jumper,Bla,2.54mm,30u,G,DIP-2 | PINREX TECHNOLOGY CORP. | 201-71-01DB00 |  | G |  |  |  |  |  |  |  |
|  |  |  |  |  | 408 | 34066N500-600-G |  | CONN,Header,Jumper,1X2,V/T,Bla,2.54mm,G/F,G,DIP-2 | FOXCONN TECHNOLOGY CO.,LTD. | SJ0520F-A0 |  | G |  |  |  |  |  |  |  |
| Sole | N | ND | N | 409 | 409 | 340692800-309-G |  | CONN,Header,Socket,2X30,V/T,Bla,0.5mm,G/F,G,SMD-60 | SAMTEC INC. | QSH-030-01-F-D-A-K-TR | 2 | G | J2,J6 |  |  |  |  |  |  |
| Sole | ND |  | N | 410 | 410 | 340459T00-GRS-G |  | CONN,I/O,HDMI,V/T,Bla,0.5mm,1u,G,SMD-19 | LOTES CO LTD | AHDM0001-P004A | 1 | G | J8 |  |  |  |  |  |  |
| Sole | ND | ND | N | 411 | 411 | 3406A2A00-309-G |  | CONN,Header,Shrouded,2X4,V/T,1.27mm,15u,G,SMD-8 | SAMTEC INC. | TFM-104-02-L-D-K-TR | 1 | G | J9 |  |  |  |  |  |  |
| Single | ND |  | N | 412 | 412 | 3406B5J00-317-G |  | CONN,Header,Socket,V/T,Bla,2mm,15u,G,DIP-18 | MOLEX INCORPORATED | 79107-7008 | 1 | G | J10 |  |  |  |  |  |  |
| Multi | ND |  | N | 413 | 413 | 3406AEU00-245-G |  | CONN,Header,Shrouded,2X4,R/A,Bla,2.54mm,G/F,G,DIP-8 | AMPHENOL SHANGHAI CORP. | G821EU208AGN00Y | 1 | G | J11 |  |  |  |  |  |  |
|  |  |  |  |  | 413 | 3406AYC00-GRT-G |  | Header&Socket Connector,511-90-08GB00,Shrouded Header,8,DIP,NY9T,2.54mm,3u",Black,G | PINREX TECHNOLOGY CORP. | 511-90-08GB00 |  | G |  |  |  |  |  |  |  |
|  |  |  |  |  | 413 | 3406AYE00-637-G |  | Header&Socket Connector,3112110800-0231,Shrouded Header,8,DIP,NY6T,2.54mm,3u",Black,G | LONG SHOUNG CO.,LTD. | 3112110800-0231 |  | G |  |  |  |  |  |  |  |
| Single | ND |  | N | 414 | 414 | 34064J800-317-G |  | CONN,Header,Socket,2X2,V/T,Bla,2mm,15u,G,DIP-4 | MOLEX INCORPORATED | 79107-7001 | 1 | G | J13 |  |  |  |  |  |  |
| Sole | ND |  | N | 415 | 415 | 34071AW00-245-G |  | CONN,SATA,V/T,Bla,1.27mm,15u,G,DIP-22 | AMPHENOL SHANGHAI CORP. | G16CE41210W3EU | 1 | G | J14 |  |  |  |  |  |  |
| Multi | ND | ND | N | 416 | 416 | 34031RP00-600-G |  | CONN,NGFF,R/A,Bla,0.5mm,30u,G,SMD-67 | FOXCONN TECHNOLOGY CO.,LTD. | 2E0BC23-S85BM-7H | 1 | G | J15 |  |  |  |  |  |  |
|  |  |  |  |  | 416 | 34031T300-GRS-G |  | CONN,NGFF,R/A,Bla,0.5mm,30u,G,SMD-67 | LOTES CO LTD | APCI0164-P004A |  | G |  |  |  |  |  |  |  |
| Sole | ND |  | N | 417 | 417 | 34131WS00-G78-G |  | CONN,BTB,Bla,0.8mm,7.87u,G,SMD-120 | FCI CONNECTORS HONGKONG LTD. | 10139781-122402LF | 1 | G | J16 |  |  |  |  |  |  |
| Sole | ND |  | N | 418 | 418 | 34131WT00-G78-G |  | CONN,BTB,Bla,0.8mm,7.87u,G,SMD-80 | FCI CONNECTORS HONGKONG LTD. | 10139781-082402LF | 1 | G | J17 |  |  |  |  |  |  |
| Multi | ND | ND | N | 419 | 419 | 340604M00-600-G |  | CONN,Header,Friction,1X3,V/T,Ivo,2.54mm,G,DIP-3 | FOXCONN TECHNOLOGY CO.,LTD. | HF2803E-P1 | 4 | G | J19,J20,J21,J22 |  |  |  |  |  |  |
|  |  |  |  |  | 419 | 3406AYL00-GRT-G |  | CONN,Header,WTB,1X3,V/T,Whi,2.54mm,G/F,G,DIP-3 | PINREX TECHNOLOGY CORP. | 744-81-03GW10 |  | G |  |  |  |  |  |  |  |
|  |  |  |  |  | 419 | 3406AYF00-637-G |  | CONN,Header,WTB,1X3,V/T,Whi,2.54mm,G,DIP-3 | LONG SHOUNG CO.,LTD. | 2111110300-0212 |  | G |  |  |  |  |  |  |  |
| Multi | ND |  | N | 420 | 420 | 3406A2B00-317-G |  | CONN,Header,WTB,1X4,V/T,Bla,2.54mm,15u,G,DIP-4 | MOLEX INCORPORATED | 171856-1104 | 4 | G | J23,J24,J25,J26 |  |  |  |  |  |  |
|  |  |  |  |  | 420 | 3406BJ100-278-G |  | CONN,Header,WTB,1X4,V/T,Bla,2.54mm,15u,G,DIP-4 | TYCO ELECTRONICS CORPORATION | 640456-4 |  | G |  |  |  |  |  |  |  |
|  |  |  |  |  | 420 | 3406AYG00-637-G |  | Header&Socket Connector,2111100400-0141,Wire-to-Board Header,4,DIP,NY66,2.54mm,15u",Black,G | LONG SHOUNG CO.,LTD. | 2111100400-0141 |  | G |  |  |  |  |  |  |  |
| Single | ND |  | N | 421 | 421 | 3406AMV00-317-G |  | CONN,Header,MINFIT,2X4,V/T,Bla,10mm,30u,G,DIP-8 | MOLEX INCORPORATED | 42819-4233 | 1 | G | J27 |  |  |  |  |  |  |
| Sole | ND |  | N | 422 | 422 | 34071BR00-245-G |  | CONN,SAS,V/T,0.6mm,30u,G,SMD-74 | AMPHENOL SHANGHAI CORP. | U10-K074-260T | 2 | G | J28,J31 |  |  |  |  |  |  |
| Sole | ND |  | N | 423 | 423 | 34071BS00-245-G |  | CONN,SAS,V/T,0.6mm,30u,G,SMD-74 | AMPHENOL SHANGHAI CORP. | U10-K074-26BT | 2 | G | J30,J33 |  |  |  |  |  |  |
| Multi | ND |  | N | 424 | 424 | 3406AQH00-317-G |  | CONN,Header,Pin Header,1X6,V/T,Bla,2.54mm,G,SMD-6 | MOLEX INCORPORATED | 87898-0656 | 5 | G | J35,J37,J39,J42,J45 |  |  |  |  |  |  |
|  |  |  |  |  | 424 | 3406BAS00-245-G |  | CONN,Header,Pin Header,1X6,V/T,Bla,2.54mm,G,SMD-6 | AMPHENOL SHANGHAI CORP. | G800MR302032HR |  | G |  |  |  |  |  |  |  |
|  |  |  |  |  | 424 | 3406A9F00-GRT-G |  | Header&Socket Connector,212-91-06GBE2,Pin Header,6,SMD,NY6T,2.54mm,3u",Black,G | PINREX TECHNOLOGY CORP. | 212-91-06GBE2 |  | G |  |  |  |  |  |  |  |
| Sole | ND |  | N | 425 | 425 | 34051FE00-GRS-G |  | CONN,Modular Jack,USBX2_RJ45,R/A,Bla/Blu,2mm,30u,G,DIP-23 | LOTES CO LTD | AUSBS002-K001C05 | 1 | G | J99 |  |  |  |  |  |  |
| Sole | ND |  | N | 426 | 426 | 3406ARP00-317-G |  | CONN,Header,Power,2X8,V/T,Whi,4.2mm,G,DIP-16 | MOLEX INCORPORATED | 46015-1602 | 1 | G | J100 |  |  |  |  |  |  |
| Multi | ND | ND | N | 427 | 427 | 34062MW00-309-G |  | CONN,Header,WTB,2X5,V/T,Bla,1.27mm,10u,G,SMD-10 | SAMTEC INC. | FTSH-105-01-L-DV-K-P-TR | 1 | G | J101 |  |  |  |  |  |  |
|  |  |  |  |  | 427 | 3406AR700-GRT-G |  | Header&Socket Connector,232-9B-05SBEC,Pin Header,10,SMD,NY6T,1.27mm,10u",Black,G | PINREX TECHNOLOGY CORP. | 232-9B-05SBEC |  | G |  |  |  |  |  |  |  |
| Sole | Y |  | N | 428 | 428 | 34051HQ00-48U-G |  | CONN,Modular Jack,RJ45X1,R/A,Bla,1.27mm,50u,G,DIP-14 | TRP CONNECTOR B.V. | 1840484-1 | 1 | G | LAN1 |  |  |  |  |  |  |
| Multi | ND | ND | N | 429 | 429 | 340634U00-600-G |  | CONN,Pin Header,2X3,V/T,Bla,2.54mm,30u,G,SMD-6 | FOXCONN TECHNOLOGY CO.,LTD. | HS1103H-RN | 6 | G | PBMJ1,PBEJ1,PBAJ1,PAMJ1,PAEJ1,PAAJ1 |  |  |  |  |  |  |
|  |  |  |  |  | 429 | 34068GL00-317-G |  | CONN,Header,Pin Header,2X3,V/T,Bla,2.54mm,30u,SMD-6 | MOLEX INCORPORATED | 015-91-6063 |  | G |  |  |  |  |  |  |  |
|  |  |  |  |  | 429 | 3406AY700-637-G |  | Header&Socket Connector,11006A5807,Pin Header,6,SMD,NY6T,2.54mm,30u",Black,G | LONG SHOUNG CO.,LTD. | 11006A5807 |  | G |  |  |  |  |  |  |  |
| Multi | N | ND | Y(5) | 430 | 430 | RN731ETTP5900B25 |  | RES,590Ohm,+/-0.1%,1/16W,G,SMD0402 | KOA SPEER ELECTRONICS, INC. | RN731ETTP5900B25 | 2 | G | PBAR34,PAAR34 |  |  |  |  |  |  |
|  |  |  |  |  | 430 | TNPW0402590RBEED |  | RES,590Ohm,+/-0.1%,1/16W,G,SMD0402 | VISHAY ENTER TECHNO LOGY.INC | TNPW0402590RBEED |  | G |  |  |  |  |  |  |  |
|  |  |  |  |  | 430 | ERA2AEB5900X |  | RES,590Ohm,+/-0.1%,1/16W,G,SMD0402 | PANASONIC INDUSTRIAL CO.,LTD. | ERA2AEB5900X |  | G |  |  |  |  |  |  |  |
|  |  |  |  |  | 430 | RT0402BRD07590RL |  | RES,590Ohm,+/-0.1%,1/16W,G,SMD0402 | YAGEO CORPORATION COMPONENT | RT0402BRD07590RL |  | G |  |  |  |  |  |  |  |
| Sole | N |  | N | 431 | 431 | ISL68137IRAZ-GG05 |  | IC,PWM Controller,ISL68137IRAZ-T,G,QFN-48,SMD | INTERSIL CORPORATION | ISL68137IRAZ-GG05 | 8 | G | PBMU1,PBFU1,PBEU1,PBAU1,PAMU1,PAFU1,PAEU1,PAAU1 |  |  |  |  |  |  |
| Sole | N |  | N | 432 | 432 | IR38064MTRP=GZS |  | IC,Regulator,IR38064MTRP=GZS,ADJ,35A,G,QFN-26,SMD | INTERNATIONAL RECTIFIER | IR38064MTRP=GZS | 2 | G | PBNU1,PANU1 |  |  |  |  |  |  |
| Multi | N | ND | N | 433 | 433 | 340805A00-638-G |  | CONN,Switch,tact,50mA,12V,G,SMD-2 | E-SWITCH | TL1015AF160QG | 2 | G | SW1,SW2 |  |  |  |  |  |  |
|  |  |  |  |  | 433 | 340812T00-653-G |  | CONN,Switch,tact,50mA,12V,Bla,G,SMD-2 | DIPTRONICS MANUFACTURING INC. | MPTLP2-V-T/R |  | G |  |  |  |  |  |  |  |
| Sole | ND |  | N | 434 | 434 | 34081GH00-653-G |  | CONN,Switch,tact,Brown,50mA,12V,G,DIP-4 | DIPTRONICS MANUFACTURING INC. | DTSA-644N-Q | 2 | G | SW3,SW4 |  |  |  |  |  |  |
| Sole |  |  |  | 435 | 435 | 340109B00-600-G |  | POWER9 CPU Socket for LGA3899-HYBRID | FOXCONN TECHNOLOGY CO.,LTD. | PE38993-51BC1-1H | 2 | G | U1,U10 |  |  |  |  |  |  |
| Sole | ND |  | Y(1) | 436 | 436 | UCD90160RGCR-C13 |  | IC,Power Controller,UCD90160RGCR,G,VQFN-64,SMD | TEXAS INSTRUMENTS | UCD90160RGCR-C13 | 1 | G | U5 |  |  |  |  |  |  |
| Sole | ND | ND | N | 437 | 437 | 34061E400-GRS-G |  | CONN,Socket,SPI Flash,V/T,Bla,1.27mm,G/F,G,SMD-16 | LOTES CO LTD | ACA-SPI-006-F01 | 2 | G | U22,U23 |  |  |  |  |  |  |
